G04 ================== begin FILE IDENTIFICATION RECORD ==================*
G04 Layout Name:  12433-1M.brd*
G04 Film Name:    NOTICE*
G04 File Format:  Gerber RS274X*
G04 File Origin:  Cadence Allegro 16.2-S037*
G04 Origin Date:  Fri Dec 07 18:55:09 2012*
G04 *
G04 Layer:  MANUFACTURING/THERMAL*
G04 *
G04 Offset:    (0.00 0.00)*
G04 Mirror:    No*
G04 Mode:      Positive*
G04 Rotation:  0*
G04 FullContactRelief:  No*
G04 UndefLineWidth:     6.00*
G04 ================== end FILE IDENTIFICATION RECORD ====================*
%FSLAX35Y35*MOIN*%
%IR0*IPPOS*OFA0.00000B0.00000*MIA0B0*SFA1.00000B1.00000*%
%ADD10C,.02*%
%ADD11C,.015*%
%ADD12C,.006*%
G75*
%LPD*%
G75*
G36*
G01X-116382Y1260682D02*
G02X-137928Y1282228I7501J29047D01*
G01X-143068Y1282229D01*
G03X-116381Y1255542I34187J7500D01*
G01X-116382Y1260682D01*
G37*
G36*
G01X-137928Y1297229D02*
G02X-116382Y1318776I29047J-7500D01*
G01X-116381Y1323916D01*
G03X-143068Y1297228I7500J-34187D01*
G01X-137928Y1297229D01*
G37*
G36*
G01X-61511Y810610D02*
G02X-89070Y848167I11812J37557D01*
G01Y863915D01*
X-83165D01*
Y848167D01*
G03X-61511Y816856I33464J0D01*
G01Y810610D01*
G37*
G36*
G01X-89070Y903285D02*
Y919033D01*
G02X-61511Y956590I39371J0D01*
G01Y950344D01*
G03X-83165Y919033I11810J-31311D01*
G01Y903285D01*
X-89070D01*
G37*
G36*
G01X-79834Y1282228D02*
G02X-101381Y1260682I-29047J7501D01*
G01X-101382Y1255542D01*
G03X-74694Y1282229I-7499J34187D01*
G01X-79834Y1282228D01*
G37*
G36*
G01X-101381Y1318776D02*
G02X-79834Y1297229I-7500J-29047D01*
G01X-74694Y1297228D01*
G03X-101382Y1323916I-34187J-7499D01*
G01X-101381Y1318776D01*
G37*
G36*
G01X-37889Y810610D02*
Y816856D01*
G03X-16235Y848167I-11810J31311D01*
G01Y863915D01*
X-10330D01*
Y848167D01*
G02X-37889Y810610I-39371J0D01*
G37*
G36*
G01X-16235Y903285D02*
Y919033D01*
G03X-37889Y950344I-33464J0D01*
G01Y956590D01*
G02X-10330Y919033I-11812J-37557D01*
G01Y903285D01*
X-16235D01*
G37*
G54D10*
G01X-284108Y651800D02*
Y664300D01*
X-276192D01*
G01X-279108Y658258D02*
X-284108D01*
G01X-264650Y651800D02*
X-265900Y652008D01*
X-267150Y652841D01*
X-267984Y654300D01*
X-268400Y655967D01*
X-267984Y657633D01*
X-267150Y659092D01*
X-265900Y659925D01*
X-264650Y660133D01*
X-263400Y659925D01*
X-262150Y659092D01*
X-261317Y657633D01*
X-261108Y655967D01*
X-261317Y654300D01*
X-262150Y652841D01*
X-263400Y652008D01*
X-264650Y651800D01*
G01X-252067D02*
Y660133D01*
G01Y658467D02*
X-251025Y659300D01*
X-249983Y659925D01*
X-248525Y660133D01*
X-247483Y659925D01*
X-246233Y659300D01*
G01X-222108Y662217D02*
X-220858Y663466D01*
X-219400Y664092D01*
X-217733Y664300D01*
X-215650Y663883D01*
X-214192Y662842D01*
X-213775Y661592D01*
X-213983Y660341D01*
X-214817Y659300D01*
X-218983Y657217D01*
X-220858Y655758D01*
X-222108Y653675D01*
X-222525Y651800D01*
X-213775D01*
G01X-203067D02*
X-202650Y654508D01*
X-202025Y656800D01*
X-201192Y658883D01*
X-200150Y661175D01*
X-198483Y664300D01*
X-206817D01*
G01X-184650Y651800D02*
Y664300D01*
X-192359Y655342D01*
X-181941D01*
G01X-176025Y651800D02*
X-167275Y664300D01*
G01X-176025D02*
X-167275Y651800D01*
G01X-143567Y648675D02*
X-142108Y647842D01*
X-140442Y647633D01*
X-138983Y647842D01*
X-137733Y648883D01*
X-136900Y650342D01*
Y660133D01*
G01Y658467D02*
X-137733Y659300D01*
X-138983Y659925D01*
X-140442Y660133D01*
X-142108Y659717D01*
X-143150Y658883D01*
X-143984Y657425D01*
X-144400Y655967D01*
X-144192Y654716D01*
X-143358Y653258D01*
X-142108Y652217D01*
X-140442Y651800D01*
X-139192Y652008D01*
X-137733Y652841D01*
X-136900Y653675D01*
G01X-128275Y657425D02*
X-121608D01*
X-122233Y658883D01*
X-123275Y659717D01*
X-124733Y660133D01*
X-126192Y659925D01*
X-127442Y659300D01*
X-128275Y657842D01*
X-128692Y656591D01*
Y655342D01*
X-128275Y654092D01*
X-127233Y652841D01*
X-125983Y652008D01*
X-124525Y651800D01*
X-123067Y652217D01*
X-121608Y653466D01*
G01X-112567Y651800D02*
Y660133D01*
G01Y658467D02*
X-111525Y659300D01*
X-110483Y659925D01*
X-109025Y660133D01*
X-107983Y659925D01*
X-106733Y659300D01*
G01X-97900Y651800D02*
Y664300D01*
G01Y658050D02*
X-96858Y659300D01*
X-95608Y659925D01*
X-94358Y660133D01*
X-92483Y659717D01*
X-91233Y658883D01*
X-90400Y657425D01*
Y655758D01*
X-90817Y654092D01*
X-91650Y652841D01*
X-93108Y652008D01*
X-94358Y651800D01*
X-95608Y652008D01*
X-96858Y652633D01*
X-97900Y653675D01*
G01X-81775Y657425D02*
X-75108D01*
X-75733Y658883D01*
X-76775Y659717D01*
X-78233Y660133D01*
X-79692Y659925D01*
X-80942Y659300D01*
X-81775Y657842D01*
X-82192Y656591D01*
Y655342D01*
X-81775Y654092D01*
X-80733Y652841D01*
X-79483Y652008D01*
X-78025Y651800D01*
X-76567Y652217D01*
X-75108Y653466D01*
G01X-66067Y651800D02*
Y660133D01*
G01Y658467D02*
X-65025Y659300D01*
X-63983Y659925D01*
X-62525Y660133D01*
X-61483Y659925D01*
X-60233Y659300D01*
G01X-33400Y651800D02*
Y662425D01*
X-32983Y663466D01*
X-32150Y664092D01*
X-30900Y664300D01*
X-29650Y663883D01*
X-29025Y662842D01*
G01X-31525Y659300D02*
X-35692D01*
G01X-16650Y651800D02*
X-17900Y652008D01*
X-19150Y652841D01*
X-19984Y654300D01*
X-20400Y655967D01*
X-19984Y657633D01*
X-19150Y659092D01*
X-17900Y659925D01*
X-16650Y660133D01*
X-15400Y659925D01*
X-14150Y659092D01*
X-13317Y657633D01*
X-13108Y655967D01*
X-13317Y654300D01*
X-14150Y652841D01*
X-15400Y652008D01*
X-16650Y651800D01*
G01X-4067D02*
Y660133D01*
G01Y658467D02*
X-3025Y659300D01*
X-1983Y659925D01*
X-525Y660133D01*
X517Y659925D01*
X1767Y659300D01*
G01X8100Y651800D02*
Y660133D01*
G01Y657842D02*
X8725Y658883D01*
X9767Y659717D01*
X11225Y660133D01*
X12683Y659717D01*
X13725Y658883D01*
X14350Y657842D01*
Y651800D01*
G01Y657842D02*
X14975Y658883D01*
X16017Y659717D01*
X17475Y660133D01*
X18933Y659717D01*
X19975Y658883D01*
X20600Y657633D01*
Y651800D01*
G01X33600D02*
Y660133D01*
G01Y658675D02*
X32767Y659508D01*
X31517Y659925D01*
X30058Y660133D01*
X28600Y659717D01*
X27350Y658883D01*
X26516Y657633D01*
X26100Y655967D01*
X26516Y654300D01*
X27350Y653050D01*
X28600Y652217D01*
X30058Y651800D01*
X31517Y652008D01*
X32767Y652633D01*
X33600Y653466D01*
G01X45350Y664300D02*
Y651800D01*
G01X42433Y660133D02*
X48267D01*
G01X76350Y664300D02*
Y651800D01*
G01X73433Y660133D02*
X79267D01*
G01X88308Y651800D02*
Y664300D01*
G01Y658258D02*
X89350Y659300D01*
X90392Y659925D01*
X92058Y660133D01*
X93308Y659925D01*
X94767Y659092D01*
X95392Y657842D01*
Y651800D01*
G01X104225Y657425D02*
X110892D01*
X110267Y658883D01*
X109225Y659717D01*
X107767Y660133D01*
X106308Y659925D01*
X105058Y659300D01*
X104225Y657842D01*
X103808Y656591D01*
Y655342D01*
X104225Y654092D01*
X105267Y652841D01*
X106517Y652008D01*
X107975Y651800D01*
X109433Y652217D01*
X110892Y653466D01*
G01X119933Y651800D02*
Y660133D01*
G01Y658467D02*
X120975Y659300D01*
X122017Y659925D01*
X123475Y660133D01*
X124517Y659925D01*
X125767Y659300D01*
G01X132100Y651800D02*
Y660133D01*
G01Y657842D02*
X132725Y658883D01*
X133767Y659717D01*
X135225Y660133D01*
X136683Y659717D01*
X137725Y658883D01*
X138350Y657842D01*
Y651800D01*
G01Y657842D02*
X138975Y658883D01*
X140017Y659717D01*
X141475Y660133D01*
X142933Y659717D01*
X143975Y658883D01*
X144600Y657633D01*
Y651800D01*
G01X157600D02*
Y660133D01*
G01Y658675D02*
X156767Y659508D01*
X155517Y659925D01*
X154058Y660133D01*
X152600Y659717D01*
X151350Y658883D01*
X150516Y657633D01*
X150100Y655967D01*
X150516Y654300D01*
X151350Y653050D01*
X152600Y652217D01*
X154058Y651800D01*
X155517Y652008D01*
X156767Y652633D01*
X157600Y653466D01*
G01X169350Y651800D02*
Y664300D01*
G01X197433Y651800D02*
Y660133D01*
G01Y658467D02*
X198475Y659300D01*
X199517Y659925D01*
X200975Y660133D01*
X202017Y659925D01*
X203267Y659300D01*
G01X212725Y657425D02*
X219392D01*
X218767Y658883D01*
X217725Y659717D01*
X216267Y660133D01*
X214808Y659925D01*
X213558Y659300D01*
X212725Y657842D01*
X212308Y656591D01*
Y655342D01*
X212725Y654092D01*
X213767Y652841D01*
X215017Y652008D01*
X216475Y651800D01*
X217933Y652217D01*
X219392Y653466D01*
G01X231350Y651800D02*
Y664300D01*
G01X246850Y660133D02*
Y651800D01*
G01Y663466D02*
X246433Y663675D01*
Y664092D01*
X246850Y664300D01*
X247267Y664092D01*
Y663675D01*
X246850Y663466D01*
G01X259225Y657425D02*
X265892D01*
X265267Y658883D01*
X264225Y659717D01*
X262767Y660133D01*
X261308Y659925D01*
X260058Y659300D01*
X259225Y657842D01*
X258808Y656591D01*
Y655342D01*
X259225Y654092D01*
X260267Y652841D01*
X261517Y652008D01*
X262975Y651800D01*
X264433Y652217D01*
X265892Y653466D01*
G01X276600Y651800D02*
Y662425D01*
X277017Y663466D01*
X277850Y664092D01*
X279100Y664300D01*
X280350Y663883D01*
X280975Y662842D01*
G01X278475Y659300D02*
X274308D01*
G01X-281400Y630100D02*
Y640725D01*
X-280983Y641766D01*
X-280150Y642392D01*
X-278900Y642600D01*
X-277650Y642183D01*
X-277025Y641142D01*
G01X-279525Y637600D02*
X-283692D01*
G01X-264650Y630100D02*
X-265900Y630308D01*
X-267150Y631141D01*
X-267984Y632600D01*
X-268400Y634267D01*
X-267984Y635933D01*
X-267150Y637392D01*
X-265900Y638225D01*
X-264650Y638433D01*
X-263400Y638225D01*
X-262150Y637392D01*
X-261317Y635933D01*
X-261108Y634267D01*
X-261317Y632600D01*
X-262150Y631141D01*
X-263400Y630308D01*
X-264650Y630100D01*
G01X-249150D02*
Y642600D01*
G01X-233650Y630100D02*
Y642600D01*
G01X-218150Y630100D02*
X-219400Y630308D01*
X-220650Y631141D01*
X-221484Y632600D01*
X-221900Y634267D01*
X-221484Y635933D01*
X-220650Y637392D01*
X-219400Y638225D01*
X-218150Y638433D01*
X-216900Y638225D01*
X-215650Y637392D01*
X-214817Y635933D01*
X-214608Y634267D01*
X-214817Y632600D01*
X-215650Y631141D01*
X-216900Y630308D01*
X-218150Y630100D01*
G01X-207859Y638433D02*
X-205358Y630100D01*
X-202650Y638433D01*
X-199942Y630100D01*
X-197441Y638433D01*
G01X-174567Y626975D02*
X-173108Y626142D01*
X-171442Y625933D01*
X-169983Y626142D01*
X-168733Y627183D01*
X-167900Y628642D01*
Y638433D01*
G01Y636767D02*
X-168733Y637600D01*
X-169983Y638225D01*
X-171442Y638433D01*
X-173108Y638017D01*
X-174150Y637183D01*
X-174984Y635725D01*
X-175400Y634267D01*
X-175192Y633016D01*
X-174358Y631558D01*
X-173108Y630517D01*
X-171442Y630100D01*
X-170192Y630308D01*
X-168733Y631141D01*
X-167900Y631975D01*
G01X-159275Y635725D02*
X-152608D01*
X-153233Y637183D01*
X-154275Y638017D01*
X-155733Y638433D01*
X-157192Y638225D01*
X-158442Y637600D01*
X-159275Y636142D01*
X-159692Y634891D01*
Y633642D01*
X-159275Y632392D01*
X-158233Y631141D01*
X-156983Y630308D01*
X-155525Y630100D01*
X-154067Y630517D01*
X-152608Y631766D01*
G01X-143567Y630100D02*
Y638433D01*
G01Y636767D02*
X-142525Y637600D01*
X-141483Y638225D01*
X-140025Y638433D01*
X-138983Y638225D01*
X-137733Y637600D01*
G01X-128900Y630100D02*
Y642600D01*
G01Y636350D02*
X-127858Y637600D01*
X-126608Y638225D01*
X-125358Y638433D01*
X-123483Y638017D01*
X-122233Y637183D01*
X-121400Y635725D01*
Y634058D01*
X-121817Y632392D01*
X-122650Y631141D01*
X-124108Y630308D01*
X-125358Y630100D01*
X-126608Y630308D01*
X-127858Y630933D01*
X-128900Y631975D01*
G01X-112775Y635725D02*
X-106108D01*
X-106733Y637183D01*
X-107775Y638017D01*
X-109233Y638433D01*
X-110692Y638225D01*
X-111942Y637600D01*
X-112775Y636142D01*
X-113192Y634891D01*
Y633642D01*
X-112775Y632392D01*
X-111733Y631141D01*
X-110483Y630308D01*
X-109025Y630100D01*
X-107567Y630517D01*
X-106108Y631766D01*
G01X-97067Y630100D02*
Y638433D01*
G01Y636767D02*
X-96025Y637600D01*
X-94983Y638225D01*
X-93525Y638433D01*
X-92483Y638225D01*
X-91233Y637600D01*
G01X-59400Y642600D02*
Y630100D01*
G01Y631975D02*
X-60233Y630933D01*
X-61483Y630308D01*
X-62942Y630100D01*
X-64608Y630517D01*
X-65858Y631558D01*
X-66692Y632808D01*
X-66900Y634267D01*
X-66692Y635725D01*
X-65858Y636975D01*
X-64608Y638017D01*
X-62942Y638433D01*
X-61483Y638225D01*
X-60442Y637808D01*
X-59400Y636975D01*
G01X-50775Y635725D02*
X-44108D01*
X-44733Y637183D01*
X-45775Y638017D01*
X-47233Y638433D01*
X-48692Y638225D01*
X-49942Y637600D01*
X-50775Y636142D01*
X-51192Y634891D01*
Y633642D01*
X-50775Y632392D01*
X-49733Y631141D01*
X-48483Y630308D01*
X-47025Y630100D01*
X-45567Y630517D01*
X-44108Y631766D01*
G01X-35275Y631558D02*
X-34233Y630725D01*
X-32775Y630100D01*
X-31525D01*
X-30275Y630517D01*
X-29442Y631141D01*
X-29025Y631975D01*
X-29233Y633225D01*
X-30067Y633850D01*
X-33817Y635100D01*
X-34650Y636558D01*
X-34233Y637600D01*
X-33400Y638225D01*
X-32150Y638433D01*
X-30900Y638225D01*
X-29650Y637600D01*
G01X-16650Y638433D02*
Y630100D01*
G01Y641766D02*
X-17067Y641975D01*
Y642392D01*
X-16650Y642600D01*
X-16233Y642392D01*
Y641975D01*
X-16650Y641766D01*
G01X-4067Y626975D02*
X-2608Y626142D01*
X-942Y625933D01*
X517Y626142D01*
X1767Y627183D01*
X2600Y628642D01*
Y638433D01*
G01Y636767D02*
X1767Y637600D01*
X517Y638225D01*
X-942Y638433D01*
X-2608Y638017D01*
X-3650Y637183D01*
X-4484Y635725D01*
X-4900Y634267D01*
X-4692Y633016D01*
X-3858Y631558D01*
X-2608Y630517D01*
X-942Y630100D01*
X308Y630308D01*
X1767Y631141D01*
X2600Y631975D01*
G01X10808Y630100D02*
Y638433D01*
G01Y636350D02*
X11642Y637392D01*
X12892Y638225D01*
X14558Y638433D01*
X16017Y638225D01*
X17267Y637392D01*
X17892Y635933D01*
Y630100D01*
G01X-274508Y1105700D02*
Y1118200D01*
X-266592D01*
G01X-269508Y1112158D02*
X-274508D01*
G01X-255050Y1105700D02*
X-256300Y1105908D01*
X-257550Y1106741D01*
X-258384Y1108200D01*
X-258800Y1109867D01*
X-258384Y1111533D01*
X-257550Y1112992D01*
X-256300Y1113825D01*
X-255050Y1114033D01*
X-253800Y1113825D01*
X-252550Y1112992D01*
X-251717Y1111533D01*
X-251508Y1109867D01*
X-251717Y1108200D01*
X-252550Y1106741D01*
X-253800Y1105908D01*
X-255050Y1105700D01*
G01X-242467D02*
Y1114033D01*
G01Y1112367D02*
X-241425Y1113200D01*
X-240383Y1113825D01*
X-238925Y1114033D01*
X-237883Y1113825D01*
X-236633Y1113200D01*
G01X-212508Y1116117D02*
X-211258Y1117366D01*
X-209800Y1117992D01*
X-208133Y1118200D01*
X-206050Y1117783D01*
X-204592Y1116742D01*
X-204175Y1115492D01*
X-204383Y1114241D01*
X-205217Y1113200D01*
X-209383Y1111117D01*
X-211258Y1109658D01*
X-212508Y1107575D01*
X-212925Y1105700D01*
X-204175D01*
G01X-193467D02*
X-193050Y1108408D01*
X-192425Y1110700D01*
X-191592Y1112783D01*
X-190550Y1115075D01*
X-188883Y1118200D01*
X-197217D01*
G01X-175050Y1105700D02*
Y1118200D01*
X-182759Y1109242D01*
X-172341D01*
G01X-166425Y1105700D02*
X-157675Y1118200D01*
G01X-166425D02*
X-157675Y1105700D01*
G01X-133967Y1102575D02*
X-132508Y1101742D01*
X-130842Y1101533D01*
X-129383Y1101742D01*
X-128133Y1102783D01*
X-127300Y1104242D01*
Y1114033D01*
G01Y1112367D02*
X-128133Y1113200D01*
X-129383Y1113825D01*
X-130842Y1114033D01*
X-132508Y1113617D01*
X-133550Y1112783D01*
X-134384Y1111325D01*
X-134800Y1109867D01*
X-134592Y1108616D01*
X-133758Y1107158D01*
X-132508Y1106117D01*
X-130842Y1105700D01*
X-129592Y1105908D01*
X-128133Y1106741D01*
X-127300Y1107575D01*
G01X-118675Y1111325D02*
X-112008D01*
X-112633Y1112783D01*
X-113675Y1113617D01*
X-115133Y1114033D01*
X-116592Y1113825D01*
X-117842Y1113200D01*
X-118675Y1111742D01*
X-119092Y1110491D01*
Y1109242D01*
X-118675Y1107992D01*
X-117633Y1106741D01*
X-116383Y1105908D01*
X-114925Y1105700D01*
X-113467Y1106117D01*
X-112008Y1107366D01*
G01X-102967Y1105700D02*
Y1114033D01*
G01Y1112367D02*
X-101925Y1113200D01*
X-100883Y1113825D01*
X-99425Y1114033D01*
X-98383Y1113825D01*
X-97133Y1113200D01*
G01X-88300Y1105700D02*
Y1118200D01*
G01Y1111950D02*
X-87258Y1113200D01*
X-86008Y1113825D01*
X-84758Y1114033D01*
X-82883Y1113617D01*
X-81633Y1112783D01*
X-80800Y1111325D01*
Y1109658D01*
X-81217Y1107992D01*
X-82050Y1106741D01*
X-83508Y1105908D01*
X-84758Y1105700D01*
X-86008Y1105908D01*
X-87258Y1106533D01*
X-88300Y1107575D01*
G01X-72175Y1111325D02*
X-65508D01*
X-66133Y1112783D01*
X-67175Y1113617D01*
X-68633Y1114033D01*
X-70092Y1113825D01*
X-71342Y1113200D01*
X-72175Y1111742D01*
X-72592Y1110491D01*
Y1109242D01*
X-72175Y1107992D01*
X-71133Y1106741D01*
X-69883Y1105908D01*
X-68425Y1105700D01*
X-66967Y1106117D01*
X-65508Y1107366D01*
G01X-56467Y1105700D02*
Y1114033D01*
G01Y1112367D02*
X-55425Y1113200D01*
X-54383Y1113825D01*
X-52925Y1114033D01*
X-51883Y1113825D01*
X-50633Y1113200D01*
G01X-23800Y1105700D02*
Y1116325D01*
X-23383Y1117366D01*
X-22550Y1117992D01*
X-21300Y1118200D01*
X-20050Y1117783D01*
X-19425Y1116742D01*
G01X-21925Y1113200D02*
X-26092D01*
G01X-7050Y1105700D02*
X-8300Y1105908D01*
X-9550Y1106741D01*
X-10384Y1108200D01*
X-10800Y1109867D01*
X-10384Y1111533D01*
X-9550Y1112992D01*
X-8300Y1113825D01*
X-7050Y1114033D01*
X-5800Y1113825D01*
X-4550Y1112992D01*
X-3717Y1111533D01*
X-3508Y1109867D01*
X-3717Y1108200D01*
X-4550Y1106741D01*
X-5800Y1105908D01*
X-7050Y1105700D01*
G01X5533D02*
Y1114033D01*
G01Y1112367D02*
X6575Y1113200D01*
X7617Y1113825D01*
X9075Y1114033D01*
X10117Y1113825D01*
X11367Y1113200D01*
G01X17700Y1105700D02*
Y1114033D01*
G01Y1111742D02*
X18325Y1112783D01*
X19367Y1113617D01*
X20825Y1114033D01*
X22283Y1113617D01*
X23325Y1112783D01*
X23950Y1111742D01*
Y1105700D01*
G01Y1111742D02*
X24575Y1112783D01*
X25617Y1113617D01*
X27075Y1114033D01*
X28533Y1113617D01*
X29575Y1112783D01*
X30200Y1111533D01*
Y1105700D01*
G01X43200D02*
Y1114033D01*
G01Y1112575D02*
X42367Y1113408D01*
X41117Y1113825D01*
X39658Y1114033D01*
X38200Y1113617D01*
X36950Y1112783D01*
X36116Y1111533D01*
X35700Y1109867D01*
X36116Y1108200D01*
X36950Y1106950D01*
X38200Y1106117D01*
X39658Y1105700D01*
X41117Y1105908D01*
X42367Y1106533D01*
X43200Y1107366D01*
G01X54950Y1118200D02*
Y1105700D01*
G01X52033Y1114033D02*
X57867D01*
G01X85950Y1118200D02*
Y1105700D01*
G01X83033Y1114033D02*
X88867D01*
G01X97908Y1105700D02*
Y1118200D01*
G01Y1112158D02*
X98950Y1113200D01*
X99992Y1113825D01*
X101658Y1114033D01*
X102908Y1113825D01*
X104367Y1112992D01*
X104992Y1111742D01*
Y1105700D01*
G01X113825Y1111325D02*
X120492D01*
X119867Y1112783D01*
X118825Y1113617D01*
X117367Y1114033D01*
X115908Y1113825D01*
X114658Y1113200D01*
X113825Y1111742D01*
X113408Y1110491D01*
Y1109242D01*
X113825Y1107992D01*
X114867Y1106741D01*
X116117Y1105908D01*
X117575Y1105700D01*
X119033Y1106117D01*
X120492Y1107366D01*
G01X129533Y1105700D02*
Y1114033D01*
G01Y1112367D02*
X130575Y1113200D01*
X131617Y1113825D01*
X133075Y1114033D01*
X134117Y1113825D01*
X135367Y1113200D01*
G01X141700Y1105700D02*
Y1114033D01*
G01Y1111742D02*
X142325Y1112783D01*
X143367Y1113617D01*
X144825Y1114033D01*
X146283Y1113617D01*
X147325Y1112783D01*
X147950Y1111742D01*
Y1105700D01*
G01Y1111742D02*
X148575Y1112783D01*
X149617Y1113617D01*
X151075Y1114033D01*
X152533Y1113617D01*
X153575Y1112783D01*
X154200Y1111533D01*
Y1105700D01*
G01X167200D02*
Y1114033D01*
G01Y1112575D02*
X166367Y1113408D01*
X165117Y1113825D01*
X163658Y1114033D01*
X162200Y1113617D01*
X160950Y1112783D01*
X160116Y1111533D01*
X159700Y1109867D01*
X160116Y1108200D01*
X160950Y1106950D01*
X162200Y1106117D01*
X163658Y1105700D01*
X165117Y1105908D01*
X166367Y1106533D01*
X167200Y1107366D01*
G01X178950Y1105700D02*
Y1118200D01*
G01X207033Y1105700D02*
Y1114033D01*
G01Y1112367D02*
X208075Y1113200D01*
X209117Y1113825D01*
X210575Y1114033D01*
X211617Y1113825D01*
X212867Y1113200D01*
G01X222325Y1111325D02*
X228992D01*
X228367Y1112783D01*
X227325Y1113617D01*
X225867Y1114033D01*
X224408Y1113825D01*
X223158Y1113200D01*
X222325Y1111742D01*
X221908Y1110491D01*
Y1109242D01*
X222325Y1107992D01*
X223367Y1106741D01*
X224617Y1105908D01*
X226075Y1105700D01*
X227533Y1106117D01*
X228992Y1107366D01*
G01X240950Y1105700D02*
Y1118200D01*
G01X256450Y1114033D02*
Y1105700D01*
G01Y1117366D02*
X256033Y1117575D01*
Y1117992D01*
X256450Y1118200D01*
X256867Y1117992D01*
Y1117575D01*
X256450Y1117366D01*
G01X268825Y1111325D02*
X275492D01*
X274867Y1112783D01*
X273825Y1113617D01*
X272367Y1114033D01*
X270908Y1113825D01*
X269658Y1113200D01*
X268825Y1111742D01*
X268408Y1110491D01*
Y1109242D01*
X268825Y1107992D01*
X269867Y1106741D01*
X271117Y1105908D01*
X272575Y1105700D01*
X274033Y1106117D01*
X275492Y1107366D01*
G01X286200Y1105700D02*
Y1116325D01*
X286617Y1117366D01*
X287450Y1117992D01*
X288700Y1118200D01*
X289950Y1117783D01*
X290575Y1116742D01*
G01X288075Y1113200D02*
X283908D01*
G01X-271800Y1084000D02*
Y1094625D01*
X-271383Y1095666D01*
X-270550Y1096292D01*
X-269300Y1096500D01*
X-268050Y1096083D01*
X-267425Y1095042D01*
G01X-269925Y1091500D02*
X-274092D01*
G01X-255050Y1084000D02*
X-256300Y1084208D01*
X-257550Y1085041D01*
X-258384Y1086500D01*
X-258800Y1088167D01*
X-258384Y1089833D01*
X-257550Y1091292D01*
X-256300Y1092125D01*
X-255050Y1092333D01*
X-253800Y1092125D01*
X-252550Y1091292D01*
X-251717Y1089833D01*
X-251508Y1088167D01*
X-251717Y1086500D01*
X-252550Y1085041D01*
X-253800Y1084208D01*
X-255050Y1084000D01*
G01X-239550D02*
Y1096500D01*
G01X-224050Y1084000D02*
Y1096500D01*
G01X-208550Y1084000D02*
X-209800Y1084208D01*
X-211050Y1085041D01*
X-211884Y1086500D01*
X-212300Y1088167D01*
X-211884Y1089833D01*
X-211050Y1091292D01*
X-209800Y1092125D01*
X-208550Y1092333D01*
X-207300Y1092125D01*
X-206050Y1091292D01*
X-205217Y1089833D01*
X-205008Y1088167D01*
X-205217Y1086500D01*
X-206050Y1085041D01*
X-207300Y1084208D01*
X-208550Y1084000D01*
G01X-198259Y1092333D02*
X-195758Y1084000D01*
X-193050Y1092333D01*
X-190342Y1084000D01*
X-187841Y1092333D01*
G01X-164967Y1080875D02*
X-163508Y1080042D01*
X-161842Y1079833D01*
X-160383Y1080042D01*
X-159133Y1081083D01*
X-158300Y1082542D01*
Y1092333D01*
G01Y1090667D02*
X-159133Y1091500D01*
X-160383Y1092125D01*
X-161842Y1092333D01*
X-163508Y1091917D01*
X-164550Y1091083D01*
X-165384Y1089625D01*
X-165800Y1088167D01*
X-165592Y1086916D01*
X-164758Y1085458D01*
X-163508Y1084417D01*
X-161842Y1084000D01*
X-160592Y1084208D01*
X-159133Y1085041D01*
X-158300Y1085875D01*
G01X-149675Y1089625D02*
X-143008D01*
X-143633Y1091083D01*
X-144675Y1091917D01*
X-146133Y1092333D01*
X-147592Y1092125D01*
X-148842Y1091500D01*
X-149675Y1090042D01*
X-150092Y1088791D01*
Y1087542D01*
X-149675Y1086292D01*
X-148633Y1085041D01*
X-147383Y1084208D01*
X-145925Y1084000D01*
X-144467Y1084417D01*
X-143008Y1085666D01*
G01X-133967Y1084000D02*
Y1092333D01*
G01Y1090667D02*
X-132925Y1091500D01*
X-131883Y1092125D01*
X-130425Y1092333D01*
X-129383Y1092125D01*
X-128133Y1091500D01*
G01X-119300Y1084000D02*
Y1096500D01*
G01Y1090250D02*
X-118258Y1091500D01*
X-117008Y1092125D01*
X-115758Y1092333D01*
X-113883Y1091917D01*
X-112633Y1091083D01*
X-111800Y1089625D01*
Y1087958D01*
X-112217Y1086292D01*
X-113050Y1085041D01*
X-114508Y1084208D01*
X-115758Y1084000D01*
X-117008Y1084208D01*
X-118258Y1084833D01*
X-119300Y1085875D01*
G01X-103175Y1089625D02*
X-96508D01*
X-97133Y1091083D01*
X-98175Y1091917D01*
X-99633Y1092333D01*
X-101092Y1092125D01*
X-102342Y1091500D01*
X-103175Y1090042D01*
X-103592Y1088791D01*
Y1087542D01*
X-103175Y1086292D01*
X-102133Y1085041D01*
X-100883Y1084208D01*
X-99425Y1084000D01*
X-97967Y1084417D01*
X-96508Y1085666D01*
G01X-87467Y1084000D02*
Y1092333D01*
G01Y1090667D02*
X-86425Y1091500D01*
X-85383Y1092125D01*
X-83925Y1092333D01*
X-82883Y1092125D01*
X-81633Y1091500D01*
G01X-49800Y1096500D02*
Y1084000D01*
G01Y1085875D02*
X-50633Y1084833D01*
X-51883Y1084208D01*
X-53342Y1084000D01*
X-55008Y1084417D01*
X-56258Y1085458D01*
X-57092Y1086708D01*
X-57300Y1088167D01*
X-57092Y1089625D01*
X-56258Y1090875D01*
X-55008Y1091917D01*
X-53342Y1092333D01*
X-51883Y1092125D01*
X-50842Y1091708D01*
X-49800Y1090875D01*
G01X-41175Y1089625D02*
X-34508D01*
X-35133Y1091083D01*
X-36175Y1091917D01*
X-37633Y1092333D01*
X-39092Y1092125D01*
X-40342Y1091500D01*
X-41175Y1090042D01*
X-41592Y1088791D01*
Y1087542D01*
X-41175Y1086292D01*
X-40133Y1085041D01*
X-38883Y1084208D01*
X-37425Y1084000D01*
X-35967Y1084417D01*
X-34508Y1085666D01*
G01X-25675Y1085458D02*
X-24633Y1084625D01*
X-23175Y1084000D01*
X-21925D01*
X-20675Y1084417D01*
X-19842Y1085041D01*
X-19425Y1085875D01*
X-19633Y1087125D01*
X-20467Y1087750D01*
X-24217Y1089000D01*
X-25050Y1090458D01*
X-24633Y1091500D01*
X-23800Y1092125D01*
X-22550Y1092333D01*
X-21300Y1092125D01*
X-20050Y1091500D01*
G01X-7050Y1092333D02*
Y1084000D01*
G01Y1095666D02*
X-7467Y1095875D01*
Y1096292D01*
X-7050Y1096500D01*
X-6633Y1096292D01*
Y1095875D01*
X-7050Y1095666D01*
G01X5533Y1080875D02*
X6992Y1080042D01*
X8658Y1079833D01*
X10117Y1080042D01*
X11367Y1081083D01*
X12200Y1082542D01*
Y1092333D01*
G01Y1090667D02*
X11367Y1091500D01*
X10117Y1092125D01*
X8658Y1092333D01*
X6992Y1091917D01*
X5950Y1091083D01*
X5116Y1089625D01*
X4700Y1088167D01*
X4908Y1086916D01*
X5742Y1085458D01*
X6992Y1084417D01*
X8658Y1084000D01*
X9908Y1084208D01*
X11367Y1085041D01*
X12200Y1085875D01*
G01X20408Y1084000D02*
Y1092333D01*
G01Y1090250D02*
X21242Y1091292D01*
X22492Y1092125D01*
X24158Y1092333D01*
X25617Y1092125D01*
X26867Y1091292D01*
X27492Y1089833D01*
Y1084000D01*
G01X-204633Y1405600D02*
Y1418100D01*
X-200467D01*
X-198800Y1417475D01*
X-197550Y1416642D01*
X-196508Y1415392D01*
X-195675Y1413933D01*
X-195467Y1411850D01*
X-195675Y1409767D01*
X-196508Y1408308D01*
X-197550Y1407058D01*
X-198800Y1406225D01*
X-200467Y1405600D01*
X-204633D01*
G01X-187675Y1411225D02*
X-181008D01*
X-181633Y1412683D01*
X-182675Y1413517D01*
X-184133Y1413933D01*
X-185592Y1413725D01*
X-186842Y1413100D01*
X-187675Y1411642D01*
X-188092Y1410391D01*
Y1409142D01*
X-187675Y1407892D01*
X-186633Y1406641D01*
X-185383Y1405808D01*
X-183925Y1405600D01*
X-182467Y1406017D01*
X-181008Y1407266D01*
G01X-170300Y1405600D02*
Y1416225D01*
X-169883Y1417266D01*
X-169050Y1417892D01*
X-167800Y1418100D01*
X-166550Y1417683D01*
X-165925Y1416642D01*
G01X-168425Y1413100D02*
X-172592D01*
G01X-153550Y1413933D02*
Y1405600D01*
G01Y1417266D02*
X-153967Y1417475D01*
Y1417892D01*
X-153550Y1418100D01*
X-153133Y1417892D01*
Y1417475D01*
X-153550Y1417266D01*
G01X-141592Y1405600D02*
Y1413933D01*
G01Y1411850D02*
X-140758Y1412892D01*
X-139508Y1413725D01*
X-137842Y1413933D01*
X-136383Y1413725D01*
X-135133Y1412892D01*
X-134508Y1411433D01*
Y1405600D01*
G01X-125675Y1411225D02*
X-119008D01*
X-119633Y1412683D01*
X-120675Y1413517D01*
X-122133Y1413933D01*
X-123592Y1413725D01*
X-124842Y1413100D01*
X-125675Y1411642D01*
X-126092Y1410391D01*
Y1409142D01*
X-125675Y1407892D01*
X-124633Y1406641D01*
X-123383Y1405808D01*
X-121925Y1405600D01*
X-120467Y1406017D01*
X-119008Y1407266D01*
G01X-91550Y1418100D02*
Y1405600D01*
G01X-94467Y1413933D02*
X-88633D01*
G01X-79592Y1405600D02*
Y1418100D01*
G01Y1412058D02*
X-78550Y1413100D01*
X-77508Y1413725D01*
X-75842Y1413933D01*
X-74592Y1413725D01*
X-73133Y1412892D01*
X-72508Y1411642D01*
Y1405600D01*
G01X-63675Y1411225D02*
X-57008D01*
X-57633Y1412683D01*
X-58675Y1413517D01*
X-60133Y1413933D01*
X-61592Y1413725D01*
X-62842Y1413100D01*
X-63675Y1411642D01*
X-64092Y1410391D01*
Y1409142D01*
X-63675Y1407892D01*
X-62633Y1406641D01*
X-61383Y1405808D01*
X-59925Y1405600D01*
X-58467Y1406017D01*
X-57008Y1407266D01*
G01X-47967Y1405600D02*
Y1413933D01*
G01Y1412267D02*
X-46925Y1413100D01*
X-45883Y1413725D01*
X-44425Y1413933D01*
X-43383Y1413725D01*
X-42133Y1413100D01*
G01X-35800Y1405600D02*
Y1413933D01*
G01Y1411642D02*
X-35175Y1412683D01*
X-34133Y1413517D01*
X-32675Y1413933D01*
X-31217Y1413517D01*
X-30175Y1412683D01*
X-29550Y1411642D01*
Y1405600D01*
G01Y1411642D02*
X-28925Y1412683D01*
X-27883Y1413517D01*
X-26425Y1413933D01*
X-24967Y1413517D01*
X-23925Y1412683D01*
X-23300Y1411433D01*
Y1405600D01*
G01X-10300D02*
Y1413933D01*
G01Y1412475D02*
X-11133Y1413308D01*
X-12383Y1413725D01*
X-13842Y1413933D01*
X-15300Y1413517D01*
X-16550Y1412683D01*
X-17384Y1411433D01*
X-17800Y1409767D01*
X-17384Y1408100D01*
X-16550Y1406850D01*
X-15300Y1406017D01*
X-13842Y1405600D01*
X-12383Y1405808D01*
X-11133Y1406433D01*
X-10300Y1407266D01*
G01X1450Y1405600D02*
Y1418100D01*
G01X29533Y1405600D02*
Y1413933D01*
G01Y1412267D02*
X30575Y1413100D01*
X31617Y1413725D01*
X33075Y1413933D01*
X34117Y1413725D01*
X35367Y1413100D01*
G01X44825Y1411225D02*
X51492D01*
X50867Y1412683D01*
X49825Y1413517D01*
X48367Y1413933D01*
X46908Y1413725D01*
X45658Y1413100D01*
X44825Y1411642D01*
X44408Y1410391D01*
Y1409142D01*
X44825Y1407892D01*
X45867Y1406641D01*
X47117Y1405808D01*
X48575Y1405600D01*
X50033Y1406017D01*
X51492Y1407266D01*
G01X63450Y1405600D02*
Y1418100D01*
G01X78950Y1413933D02*
Y1405600D01*
G01Y1417266D02*
X78533Y1417475D01*
Y1417892D01*
X78950Y1418100D01*
X79367Y1417892D01*
Y1417475D01*
X78950Y1417266D01*
G01X91325Y1411225D02*
X97992D01*
X97367Y1412683D01*
X96325Y1413517D01*
X94867Y1413933D01*
X93408Y1413725D01*
X92158Y1413100D01*
X91325Y1411642D01*
X90908Y1410391D01*
Y1409142D01*
X91325Y1407892D01*
X92367Y1406641D01*
X93617Y1405808D01*
X95075Y1405600D01*
X96533Y1406017D01*
X97992Y1407266D01*
G01X108700Y1405600D02*
Y1416225D01*
X109117Y1417266D01*
X109950Y1417892D01*
X111200Y1418100D01*
X112450Y1417683D01*
X113075Y1416642D01*
G01X110575Y1413100D02*
X106408D01*
G01X144283Y1412892D02*
X142825Y1413725D01*
X141575Y1413933D01*
X139908Y1413517D01*
X138658Y1412683D01*
X137825Y1411225D01*
X137616Y1409767D01*
X137825Y1408308D01*
X138658Y1407058D01*
X139908Y1406017D01*
X141575Y1405600D01*
X143033Y1406017D01*
X144283Y1406850D01*
G01X156450Y1405600D02*
X155200Y1405808D01*
X153950Y1406641D01*
X153116Y1408100D01*
X152700Y1409767D01*
X153116Y1411433D01*
X153950Y1412892D01*
X155200Y1413725D01*
X156450Y1413933D01*
X157700Y1413725D01*
X158950Y1412892D01*
X159783Y1411433D01*
X159992Y1409767D01*
X159783Y1408100D01*
X158950Y1406641D01*
X157700Y1405808D01*
X156450Y1405600D01*
G01X168408D02*
Y1413933D01*
G01Y1411850D02*
X169242Y1412892D01*
X170492Y1413725D01*
X172158Y1413933D01*
X173617Y1413725D01*
X174867Y1412892D01*
X175492Y1411433D01*
Y1405600D01*
G01X183908D02*
Y1413933D01*
G01Y1411850D02*
X184742Y1412892D01*
X185992Y1413725D01*
X187658Y1413933D01*
X189117Y1413725D01*
X190367Y1412892D01*
X190992Y1411433D01*
Y1405600D01*
G01X199825Y1411225D02*
X206492D01*
X205867Y1412683D01*
X204825Y1413517D01*
X203367Y1413933D01*
X201908Y1413725D01*
X200658Y1413100D01*
X199825Y1411642D01*
X199408Y1410391D01*
Y1409142D01*
X199825Y1407892D01*
X200867Y1406641D01*
X202117Y1405808D01*
X203575Y1405600D01*
X205033Y1406017D01*
X206492Y1407266D01*
G01X221783Y1412892D02*
X220325Y1413725D01*
X219075Y1413933D01*
X217408Y1413517D01*
X216158Y1412683D01*
X215325Y1411225D01*
X215116Y1409767D01*
X215325Y1408308D01*
X216158Y1407058D01*
X217408Y1406017D01*
X219075Y1405600D01*
X220533Y1406017D01*
X221783Y1406850D01*
G01X233950Y1418100D02*
Y1405600D01*
G01X231033Y1413933D02*
X236867D01*
G01X467467Y976983D02*
X476633Y986150D01*
G01X472050Y987817D02*
Y975317D01*
G01X476633Y976983D02*
X467467Y986150D01*
G01X465800Y981567D02*
X478300D01*
G01X482967Y976983D02*
X492133Y986150D01*
G01X487550Y987817D02*
Y975317D01*
G01X492133Y976983D02*
X482967Y986150D01*
G01X481300Y981567D02*
X493800D01*
G01X498467Y976983D02*
X507633Y986150D01*
G01X503050Y987817D02*
Y975317D01*
G01X507633Y976983D02*
X498467Y986150D01*
G01X496800Y981567D02*
X509300D01*
G01X513967Y976983D02*
X523133Y986150D01*
G01X518550Y987817D02*
Y975317D01*
G01X523133Y976983D02*
X513967Y986150D01*
G01X512300Y981567D02*
X524800D01*
G01X534050Y976983D02*
X533633Y977192D01*
Y977608D01*
X534050Y977817D01*
X534467Y977608D01*
Y977192D01*
X534050Y976983D01*
G01Y982608D02*
X533633Y982817D01*
Y983233D01*
X534050Y983442D01*
X534467Y983233D01*
Y982817D01*
X534050Y982608D01*
G01X562550Y989900D02*
X567550D01*
G01X565050D02*
Y977400D01*
G01X562550D02*
X567550D01*
G01X577633Y974275D02*
X579092Y973442D01*
X580758Y973233D01*
X582217Y973442D01*
X583467Y974483D01*
X584300Y975942D01*
Y985733D01*
G01Y984067D02*
X583467Y984900D01*
X582217Y985525D01*
X580758Y985733D01*
X579092Y985317D01*
X578050Y984483D01*
X577216Y983025D01*
X576800Y981567D01*
X577008Y980316D01*
X577842Y978858D01*
X579092Y977817D01*
X580758Y977400D01*
X582008Y977608D01*
X583467Y978441D01*
X584300Y979275D01*
G01X592508Y977400D02*
Y985733D01*
G01Y983650D02*
X593342Y984692D01*
X594592Y985525D01*
X596258Y985733D01*
X597717Y985525D01*
X598967Y984692D01*
X599592Y983233D01*
Y977400D01*
G01X611550D02*
X610300Y977608D01*
X609050Y978441D01*
X608216Y979900D01*
X607800Y981567D01*
X608216Y983233D01*
X609050Y984692D01*
X610300Y985525D01*
X611550Y985733D01*
X612800Y985525D01*
X614050Y984692D01*
X614883Y983233D01*
X615092Y981567D01*
X614883Y979900D01*
X614050Y978441D01*
X612800Y977608D01*
X611550Y977400D01*
G01X624133D02*
Y985733D01*
G01Y984067D02*
X625175Y984900D01*
X626217Y985525D01*
X627675Y985733D01*
X628717Y985525D01*
X629967Y984900D01*
G01X639425Y983025D02*
X646092D01*
X645467Y984483D01*
X644425Y985317D01*
X642967Y985733D01*
X641508Y985525D01*
X640258Y984900D01*
X639425Y983442D01*
X639008Y982191D01*
Y980942D01*
X639425Y979692D01*
X640467Y978441D01*
X641717Y977608D01*
X643175Y977400D01*
X644633Y977817D01*
X646092Y979066D01*
G01X673550Y977400D02*
Y989900D01*
X671050Y987400D01*
G01Y977400D02*
X676050D01*
G01X698300D02*
Y985733D01*
G01Y983442D02*
X698925Y984483D01*
X699967Y985317D01*
X701425Y985733D01*
X702883Y985317D01*
X703925Y984483D01*
X704550Y983442D01*
Y977400D01*
G01Y983442D02*
X705175Y984483D01*
X706217Y985317D01*
X707675Y985733D01*
X709133Y985317D01*
X710175Y984483D01*
X710800Y983233D01*
Y977400D01*
G01X720050Y985733D02*
Y977400D01*
G01Y989066D02*
X719633Y989275D01*
Y989692D01*
X720050Y989900D01*
X720467Y989692D01*
Y989275D01*
X720050Y989066D01*
G01X735550Y977400D02*
Y989900D01*
G01X761967Y977400D02*
Y989900D01*
X766133D01*
X767800Y989275D01*
X769050Y988442D01*
X770092Y987192D01*
X770925Y985733D01*
X771133Y983650D01*
X770925Y981567D01*
X770092Y980108D01*
X769050Y978858D01*
X767800Y978025D01*
X766133Y977400D01*
X761967D01*
G01X779342Y981567D02*
X784758D01*
G01X802133Y988858D02*
X800883Y989483D01*
X799425Y989900D01*
X797758D01*
X795883Y989275D01*
X794425Y988233D01*
X793383Y986983D01*
X792550Y984900D01*
X792341Y983025D01*
X792758Y981150D01*
X793383Y979900D01*
X794633Y978650D01*
X796092Y977817D01*
X797550Y977400D01*
X799008D01*
X800467Y977817D01*
X801717Y978441D01*
X802759Y979275D01*
G01X813050Y977400D02*
X811383Y977608D01*
X809925Y978441D01*
X808675Y979692D01*
X807841Y981150D01*
X807425Y982817D01*
Y984483D01*
X807841Y986150D01*
X808675Y987608D01*
X809925Y988858D01*
X811383Y989692D01*
X813050Y989900D01*
X814717Y989692D01*
X816175Y988858D01*
X817425Y987608D01*
X818259Y986150D01*
X818675Y984483D01*
Y982817D01*
X818259Y981150D01*
X817425Y979692D01*
X816175Y978441D01*
X814717Y977608D01*
X813050Y977400D01*
G01X823967D02*
Y989900D01*
X828133D01*
X829800Y989275D01*
X831050Y988442D01*
X832092Y987192D01*
X832925Y985733D01*
X833133Y983650D01*
X832925Y981567D01*
X832092Y980108D01*
X831050Y978858D01*
X829800Y978025D01*
X828133Y977400D01*
X823967D01*
G01X848217D02*
X839883D01*
Y989900D01*
X848217D01*
G01X844883Y983858D02*
X839883D01*
G01X471658Y1022300D02*
Y1034800D01*
X481242Y1022300D01*
Y1034800D01*
G01X491950Y1022300D02*
X490700Y1022508D01*
X489450Y1023341D01*
X488616Y1024800D01*
X488200Y1026467D01*
X488616Y1028133D01*
X489450Y1029592D01*
X490700Y1030425D01*
X491950Y1030633D01*
X493200Y1030425D01*
X494450Y1029592D01*
X495283Y1028133D01*
X495492Y1026467D01*
X495283Y1024800D01*
X494450Y1023341D01*
X493200Y1022508D01*
X491950Y1022300D01*
G01X507450Y1034800D02*
Y1022300D01*
G01X504533Y1030633D02*
X510367D01*
G01X519825Y1027925D02*
X526492D01*
X525867Y1029383D01*
X524825Y1030217D01*
X523367Y1030633D01*
X521908Y1030425D01*
X520658Y1029800D01*
X519825Y1028342D01*
X519408Y1027091D01*
Y1025842D01*
X519825Y1024592D01*
X520867Y1023341D01*
X522117Y1022508D01*
X523575Y1022300D01*
X525033Y1022717D01*
X526492Y1023966D01*
G01X535325Y1023758D02*
X536367Y1022925D01*
X537825Y1022300D01*
X539075D01*
X540325Y1022717D01*
X541158Y1023341D01*
X541575Y1024175D01*
X541367Y1025425D01*
X540533Y1026050D01*
X536783Y1027300D01*
X535950Y1028758D01*
X536367Y1029800D01*
X537200Y1030425D01*
X538450Y1030633D01*
X539700Y1030425D01*
X540950Y1029800D01*
G01X553950Y1021883D02*
X553533Y1022092D01*
Y1022508D01*
X553950Y1022717D01*
X554367Y1022508D01*
Y1022092D01*
X553950Y1021883D01*
G01Y1027508D02*
X553533Y1027717D01*
Y1028133D01*
X553950Y1028342D01*
X554367Y1028133D01*
Y1027717D01*
X553950Y1027508D01*
G54D11*
G01X-199967Y1205600D02*
X-206633D01*
Y1215600D01*
X-199967D01*
G01X-202633Y1210767D02*
X-206633D01*
G01X-195500Y1205600D02*
X-188500Y1215600D01*
G01X-195500D02*
X-188500Y1205600D01*
G01X-180700Y1205267D02*
X-181033Y1205433D01*
Y1205767D01*
X-180700Y1205933D01*
X-180367Y1205767D01*
Y1205433D01*
X-180700Y1205267D01*
G01Y1209766D02*
X-181033Y1209933D01*
Y1210267D01*
X-180700Y1210433D01*
X-180367Y1210267D01*
Y1209933D01*
X-180700Y1209766D01*
G01X-161267Y1205600D02*
Y1215600D01*
X-154933D01*
G01X-157267Y1210767D02*
X-161267D01*
G01X-150133Y1215600D02*
Y1205600D01*
X-143467D01*
G01X-139667D02*
X-135500Y1215600D01*
X-131333Y1205600D01*
G01X-132833Y1209100D02*
X-138167D01*
G01X-127700Y1206933D02*
X-126367Y1206100D01*
X-124867Y1205600D01*
X-123533D01*
X-122200Y1206100D01*
X-121200Y1206933D01*
X-120700Y1208100D01*
X-121033Y1209266D01*
X-121867Y1210267D01*
X-123367Y1210933D01*
X-125367Y1211267D01*
X-126533Y1211933D01*
X-127033Y1213100D01*
X-126700Y1214267D01*
X-125867Y1215100D01*
X-124700Y1215600D01*
X-123533D01*
X-122367Y1215267D01*
X-121367Y1214433D01*
G01X-116400Y1205600D02*
Y1215600D01*
G01X-109400D02*
Y1205600D01*
G01Y1210600D02*
X-116400D01*
G01X-90300Y1215600D02*
Y1205600D01*
G01X-94133Y1215600D02*
X-86467D01*
G01X-82333Y1205600D02*
Y1215600D01*
X-78167D01*
X-76833Y1215100D01*
X-76000Y1214433D01*
X-75667Y1213100D01*
X-76000Y1211767D01*
X-77000Y1210933D01*
X-78167Y1210433D01*
X-82333D01*
G01X-78167D02*
X-75667Y1205600D01*
G01X-67700D02*
Y1215600D01*
X-69700Y1213600D01*
G01Y1205600D02*
X-65700D01*
G01X-56400Y1215600D02*
X-57734Y1215267D01*
X-58733Y1214433D01*
X-59400Y1213433D01*
X-59900Y1212100D01*
X-60067Y1210600D01*
X-59900Y1209100D01*
X-59400Y1207767D01*
X-58733Y1206766D01*
X-57734Y1205933D01*
X-56400Y1205600D01*
X-55067Y1205933D01*
X-54067Y1206766D01*
X-53400Y1207767D01*
X-52900Y1209100D01*
X-52733Y1210600D01*
X-52900Y1212100D01*
X-53400Y1213433D01*
X-54067Y1214433D01*
X-55067Y1215267D01*
X-56400Y1215600D01*
G01X-48767Y1207600D02*
X-47767Y1206433D01*
X-46434Y1205767D01*
X-44933Y1205600D01*
X-43600Y1205767D01*
X-42267Y1206600D01*
X-41433Y1207600D01*
X-41267Y1208600D01*
X-41600Y1209766D01*
X-42767Y1210600D01*
X-43933Y1210933D01*
X-45433D01*
G01X-43933D02*
X-42933Y1211433D01*
X-42100Y1212266D01*
X-41767Y1213267D01*
X-42100Y1214267D01*
X-42933Y1215100D01*
X-44433Y1215600D01*
X-45933Y1215433D01*
X-47433Y1214767D01*
G01X-38800Y1202267D02*
X-28800D01*
G01X-25333Y1206766D02*
X-24167Y1205933D01*
X-22833Y1205600D01*
X-21500Y1205933D01*
X-20333Y1206933D01*
X-19500Y1208433D01*
X-19167Y1209933D01*
Y1211767D01*
X-19500Y1213267D01*
X-20333Y1214600D01*
X-21333Y1215267D01*
X-22500Y1215600D01*
X-23834Y1215267D01*
X-24833Y1214600D01*
X-25500Y1213600D01*
X-25833Y1212266D01*
X-25500Y1211100D01*
X-24667Y1209933D01*
X-23667Y1209266D01*
X-22500Y1209100D01*
X-21167Y1209433D01*
X-20167Y1210267D01*
X-19167Y1211767D01*
G01X-14867Y1207600D02*
X-13867Y1206433D01*
X-12534Y1205767D01*
X-11033Y1205600D01*
X-9700Y1205767D01*
X-8367Y1206600D01*
X-7533Y1207600D01*
X-7367Y1208600D01*
X-7700Y1209766D01*
X-8867Y1210600D01*
X-10033Y1210933D01*
X-11533D01*
G01X-10033D02*
X-9033Y1211433D01*
X-8200Y1212266D01*
X-7867Y1213267D01*
X-8200Y1214267D01*
X-9033Y1215100D01*
X-10533Y1215600D01*
X-12033Y1215433D01*
X-13533Y1214767D01*
G01X-4900Y1202267D02*
X5100D01*
G01X7733Y1207600D02*
X8733Y1206433D01*
X10066Y1205767D01*
X11567Y1205600D01*
X12900Y1205767D01*
X14233Y1206600D01*
X15067Y1207600D01*
X15233Y1208600D01*
X14900Y1209766D01*
X13733Y1210600D01*
X12567Y1210933D01*
X11067D01*
G01X12567D02*
X13567Y1211433D01*
X14400Y1212266D01*
X14733Y1213267D01*
X14400Y1214267D01*
X13567Y1215100D01*
X12067Y1215600D01*
X10567Y1215433D01*
X9067Y1214767D01*
G01X22700Y1215600D02*
X21366Y1215267D01*
X20367Y1214433D01*
X19700Y1213433D01*
X19200Y1212100D01*
X19033Y1210600D01*
X19200Y1209100D01*
X19700Y1207767D01*
X20367Y1206766D01*
X21366Y1205933D01*
X22700Y1205600D01*
X24033Y1205933D01*
X25033Y1206766D01*
X25700Y1207767D01*
X26200Y1209100D01*
X26367Y1210600D01*
X26200Y1212100D01*
X25700Y1213433D01*
X25033Y1214433D01*
X24033Y1215267D01*
X22700Y1215600D01*
G01X34000Y1205267D02*
X33667Y1205433D01*
Y1205767D01*
X34000Y1205933D01*
X34333Y1205767D01*
Y1205433D01*
X34000Y1205267D01*
G01Y1209766D02*
X33667Y1209933D01*
Y1210267D01*
X34000Y1210433D01*
X34333Y1210267D01*
Y1209933D01*
X34000Y1209766D01*
G01X-192967Y1347600D02*
X-191967Y1346433D01*
X-190634Y1345767D01*
X-189133Y1345600D01*
X-187800Y1345767D01*
X-186467Y1346600D01*
X-185633Y1347600D01*
X-185467Y1348600D01*
X-185800Y1349766D01*
X-186967Y1350600D01*
X-188133Y1350933D01*
X-189633D01*
G01X-188133D02*
X-187133Y1351433D01*
X-186300Y1352266D01*
X-185967Y1353267D01*
X-186300Y1354267D01*
X-187133Y1355100D01*
X-188633Y1355600D01*
X-190133Y1355433D01*
X-191633Y1354767D01*
G01X-178000Y1345267D02*
X-178333Y1345433D01*
Y1345767D01*
X-178000Y1345933D01*
X-177667Y1345767D01*
Y1345433D01*
X-178000Y1345267D01*
G01X-192467Y1369933D02*
X-191467Y1370933D01*
X-190300Y1371433D01*
X-188967Y1371600D01*
X-187300Y1371267D01*
X-186133Y1370433D01*
X-185800Y1369433D01*
X-185967Y1368433D01*
X-186633Y1367600D01*
X-189967Y1365933D01*
X-191467Y1364767D01*
X-192467Y1363100D01*
X-192800Y1361600D01*
X-185800D01*
G01X-178000Y1361267D02*
X-178333Y1361433D01*
Y1361767D01*
X-178000Y1361933D01*
X-177667Y1361767D01*
Y1361433D01*
X-178000Y1361267D01*
G01X-189300Y1377600D02*
Y1387600D01*
X-191300Y1385600D01*
G01Y1377600D02*
X-187300D01*
G01X-178000Y1377267D02*
X-178333Y1377433D01*
Y1377767D01*
X-178000Y1377933D01*
X-177667Y1377767D01*
Y1377433D01*
X-178000Y1377267D01*
G01X-158567Y1377600D02*
Y1387600D01*
X-152233D01*
G01X-154567Y1382767D02*
X-158567D01*
G01X-147433Y1387600D02*
Y1377600D01*
X-140767D01*
G01X-136967D02*
X-132800Y1387600D01*
X-128633Y1377600D01*
G01X-130133Y1381100D02*
X-135467D01*
G01X-125000Y1378933D02*
X-123667Y1378100D01*
X-122167Y1377600D01*
X-120833D01*
X-119500Y1378100D01*
X-118500Y1378933D01*
X-118000Y1380100D01*
X-118333Y1381266D01*
X-119167Y1382267D01*
X-120667Y1382933D01*
X-122667Y1383267D01*
X-123833Y1383933D01*
X-124333Y1385100D01*
X-124000Y1386267D01*
X-123167Y1387100D01*
X-122000Y1387600D01*
X-120833D01*
X-119667Y1387267D01*
X-118667Y1386433D01*
G01X-113700Y1377600D02*
Y1387600D01*
G01X-106700D02*
Y1377600D01*
G01Y1382600D02*
X-113700D01*
G01X-87600Y1387600D02*
Y1377600D01*
G01X-91433Y1387600D02*
X-83767D01*
G01X-79800Y1377600D02*
Y1387600D01*
G01X-72800D02*
Y1377600D01*
G01Y1382600D02*
X-79800D01*
G01X-69333Y1377600D02*
Y1387600D01*
X-65000Y1379267D01*
X-60667Y1387600D01*
Y1377600D01*
G01X-57033Y1387600D02*
Y1377600D01*
X-50367D01*
G01X-42400D02*
Y1387600D01*
X-44400Y1385600D01*
G01Y1377600D02*
X-40400D01*
G01X-31100Y1387600D02*
X-32434Y1387267D01*
X-33433Y1386433D01*
X-34100Y1385433D01*
X-34600Y1384100D01*
X-34767Y1382600D01*
X-34600Y1381100D01*
X-34100Y1379767D01*
X-33433Y1378766D01*
X-32434Y1377933D01*
X-31100Y1377600D01*
X-29767Y1377933D01*
X-28767Y1378766D01*
X-28100Y1379767D01*
X-27600Y1381100D01*
X-27433Y1382600D01*
X-27600Y1384100D01*
X-28100Y1385433D01*
X-28767Y1386433D01*
X-29767Y1387267D01*
X-31100Y1387600D01*
G01X-8500Y1377267D02*
X-8833Y1377433D01*
Y1377767D01*
X-8500Y1377933D01*
X-8167Y1377767D01*
Y1377433D01*
X-8500Y1377267D01*
G01Y1381766D02*
X-8833Y1381933D01*
Y1382267D01*
X-8500Y1382433D01*
X-8167Y1382267D01*
Y1381933D01*
X-8500Y1381766D01*
G01X10933Y1377600D02*
Y1387600D01*
X17267D01*
G01X14933Y1382767D02*
X10933D01*
G01X22567Y1384266D02*
Y1379600D01*
X23233Y1378433D01*
X24233Y1377767D01*
X25400Y1377600D01*
X26567Y1377767D01*
X27567Y1378433D01*
X28233Y1379600D01*
G01Y1377600D02*
Y1384266D01*
G01X36700Y1377600D02*
Y1387600D01*
G01X48000Y1377600D02*
Y1387600D01*
G01X73267Y1383433D02*
X72100Y1384100D01*
X71100Y1384266D01*
X69767Y1383933D01*
X68767Y1383267D01*
X68100Y1382100D01*
X67933Y1380933D01*
X68100Y1379767D01*
X68767Y1378766D01*
X69767Y1377933D01*
X71100Y1377600D01*
X72267Y1377933D01*
X73267Y1378600D01*
G01X81900Y1377600D02*
X80900Y1377767D01*
X79900Y1378433D01*
X79233Y1379600D01*
X78900Y1380933D01*
X79233Y1382267D01*
X79900Y1383433D01*
X80900Y1384100D01*
X81900Y1384266D01*
X82900Y1384100D01*
X83900Y1383433D01*
X84567Y1382267D01*
X84733Y1380933D01*
X84567Y1379600D01*
X83900Y1378433D01*
X82900Y1377767D01*
X81900Y1377600D01*
G01X90367D02*
Y1384266D01*
G01Y1382600D02*
X91033Y1383433D01*
X92033Y1384100D01*
X93367Y1384266D01*
X94533Y1384100D01*
X95533Y1383433D01*
X96033Y1382267D01*
Y1377600D01*
G01X104500Y1387600D02*
Y1377600D01*
G01X102167Y1384266D02*
X106833D01*
G01X118800Y1377600D02*
Y1384266D01*
G01Y1383100D02*
X118133Y1383767D01*
X117133Y1384100D01*
X115967Y1384266D01*
X114800Y1383933D01*
X113800Y1383267D01*
X113133Y1382267D01*
X112800Y1380933D01*
X113133Y1379600D01*
X113800Y1378600D01*
X114800Y1377933D01*
X115967Y1377600D01*
X117133Y1377767D01*
X118133Y1378267D01*
X118800Y1378933D01*
G01X129767Y1383433D02*
X128600Y1384100D01*
X127600Y1384266D01*
X126267Y1383933D01*
X125267Y1383267D01*
X124600Y1382100D01*
X124433Y1380933D01*
X124600Y1379767D01*
X125267Y1378766D01*
X126267Y1377933D01*
X127600Y1377600D01*
X128767Y1377933D01*
X129767Y1378600D01*
G01X138400Y1387600D02*
Y1377600D01*
G01X136067Y1384266D02*
X140733D01*
G01X-143667Y684900D02*
X-150333D01*
Y694900D01*
X-143667D01*
G01X-146333Y690067D02*
X-150333D01*
G01X-139200Y684900D02*
X-132200Y694900D01*
G01X-139200D02*
X-132200Y684900D01*
G01X-124400Y684567D02*
X-124733Y684733D01*
Y685067D01*
X-124400Y685233D01*
X-124067Y685067D01*
Y684733D01*
X-124400Y684567D01*
G01Y689066D02*
X-124733Y689233D01*
Y689567D01*
X-124400Y689733D01*
X-124067Y689567D01*
Y689233D01*
X-124400Y689066D01*
G01X-104967Y684900D02*
Y694900D01*
X-98633D01*
G01X-100967Y690067D02*
X-104967D01*
G01X-93833Y694900D02*
Y684900D01*
X-87167D01*
G01X-83367D02*
X-79200Y694900D01*
X-75033Y684900D01*
G01X-76533Y688400D02*
X-81867D01*
G01X-71400Y686233D02*
X-70067Y685400D01*
X-68567Y684900D01*
X-67233D01*
X-65900Y685400D01*
X-64900Y686233D01*
X-64400Y687400D01*
X-64733Y688566D01*
X-65567Y689567D01*
X-67067Y690233D01*
X-69067Y690567D01*
X-70233Y691233D01*
X-70733Y692400D01*
X-70400Y693567D01*
X-69567Y694400D01*
X-68400Y694900D01*
X-67233D01*
X-66067Y694567D01*
X-65067Y693733D01*
G01X-60100Y684900D02*
Y694900D01*
G01X-53100D02*
Y684900D01*
G01Y689900D02*
X-60100D01*
G01X-34000Y694900D02*
Y684900D01*
G01X-37833Y694900D02*
X-30167D01*
G01X-26033Y684900D02*
Y694900D01*
X-21867D01*
X-20533Y694400D01*
X-19700Y693733D01*
X-19367Y692400D01*
X-19700Y691067D01*
X-20700Y690233D01*
X-21867Y689733D01*
X-26033D01*
G01X-21867D02*
X-19367Y684900D01*
G01X-14567Y689066D02*
X-13400Y690233D01*
X-12400Y690900D01*
X-11067Y691233D01*
X-9900Y690900D01*
X-9067Y690233D01*
X-8400Y689233D01*
X-8233Y688067D01*
X-8400Y687067D01*
X-9067Y686066D01*
X-10067Y685233D01*
X-11233Y684900D01*
X-12567Y685233D01*
X-13733Y686233D01*
X-14400Y687733D01*
X-14567Y689400D01*
X-14233Y691566D01*
X-13733Y692733D01*
X-12900Y693900D01*
X-11733Y694733D01*
X-10567Y694900D01*
X-9400Y694567D01*
X-8567Y693733D01*
G01X-100Y694900D02*
X-1434Y694567D01*
X-2433Y693733D01*
X-3100Y692733D01*
X-3600Y691400D01*
X-3767Y689900D01*
X-3600Y688400D01*
X-3100Y687067D01*
X-2433Y686066D01*
X-1434Y685233D01*
X-100Y684900D01*
X1233Y685233D01*
X2233Y686066D01*
X2900Y687067D01*
X3400Y688400D01*
X3567Y689900D01*
X3400Y691400D01*
X2900Y692733D01*
X2233Y693733D01*
X1233Y694567D01*
X-100Y694900D01*
G01X7700Y684900D02*
X14700Y694900D01*
G01X7700D02*
X14700Y684900D01*
G01X22500D02*
Y694900D01*
X20500Y692900D01*
G01Y684900D02*
X24500D01*
G01X33800D02*
Y694900D01*
X31800Y692900D01*
G01Y684900D02*
X35800D01*
G01X42267Y686066D02*
X43433Y685233D01*
X44767Y684900D01*
X46100Y685233D01*
X47267Y686233D01*
X48100Y687733D01*
X48433Y689233D01*
Y691067D01*
X48100Y692567D01*
X47267Y693900D01*
X46267Y694567D01*
X45100Y694900D01*
X43766Y694567D01*
X42767Y693900D01*
X42100Y692900D01*
X41767Y691566D01*
X42100Y690400D01*
X42933Y689233D01*
X43933Y688566D01*
X45100Y688400D01*
X46433Y688733D01*
X47433Y689567D01*
X48433Y691067D01*
G01X51400Y681567D02*
X61400D01*
G01X64533Y693233D02*
X65533Y694233D01*
X66700Y694733D01*
X68033Y694900D01*
X69700Y694567D01*
X70867Y693733D01*
X71200Y692733D01*
X71033Y691733D01*
X70367Y690900D01*
X67033Y689233D01*
X65533Y688067D01*
X64533Y686400D01*
X64200Y684900D01*
X71200D01*
G01X79000Y694900D02*
X77666Y694567D01*
X76667Y693733D01*
X76000Y692733D01*
X75500Y691400D01*
X75333Y689900D01*
X75500Y688400D01*
X76000Y687067D01*
X76667Y686066D01*
X77666Y685233D01*
X79000Y684900D01*
X80333Y685233D01*
X81333Y686066D01*
X82000Y687067D01*
X82500Y688400D01*
X82667Y689900D01*
X82500Y691400D01*
X82000Y692733D01*
X81333Y693733D01*
X80333Y694567D01*
X79000Y694900D01*
G01X86800Y684900D02*
X93800Y694900D01*
G01X86800D02*
X93800Y684900D01*
G01X97933Y686900D02*
X98933Y685733D01*
X100266Y685067D01*
X101767Y684900D01*
X103100Y685067D01*
X104433Y685900D01*
X105267Y686900D01*
X105433Y687900D01*
X105100Y689066D01*
X103933Y689900D01*
X102767Y690233D01*
X101267D01*
G01X102767D02*
X103767Y690733D01*
X104600Y691566D01*
X104933Y692567D01*
X104600Y693567D01*
X103767Y694400D01*
X102267Y694900D01*
X100767Y694733D01*
X99267Y694067D01*
G01X112900Y694900D02*
X111566Y694567D01*
X110567Y693733D01*
X109900Y692733D01*
X109400Y691400D01*
X109233Y689900D01*
X109400Y688400D01*
X109900Y687067D01*
X110567Y686066D01*
X111566Y685233D01*
X112900Y684900D01*
X114233Y685233D01*
X115233Y686066D01*
X115900Y687067D01*
X116400Y688400D01*
X116567Y689900D01*
X116400Y691400D01*
X115900Y692733D01*
X115233Y693733D01*
X114233Y694567D01*
X112900Y694900D01*
G01X-126967Y710900D02*
X-133633D01*
Y720900D01*
X-126967D01*
G01X-129633Y716067D02*
X-133633D01*
G01X-119000Y710567D02*
X-119333Y710733D01*
Y711067D01*
X-119000Y711233D01*
X-118667Y711067D01*
Y710733D01*
X-119000Y710567D01*
G01Y715066D02*
X-119333Y715233D01*
Y715567D01*
X-119000Y715733D01*
X-118667Y715567D01*
Y715233D01*
X-119000Y715066D01*
G01X-154033Y734700D02*
Y744700D01*
X-146367Y734700D01*
Y744700D01*
G01X-143067Y734700D02*
X-138900Y744700D01*
X-134733Y734700D01*
G01X-136233Y738200D02*
X-141567D01*
G01X-131933Y734700D02*
Y744700D01*
X-127600Y736367D01*
X-123267Y744700D01*
Y734700D01*
G01X-112967D02*
X-119633D01*
Y744700D01*
X-112967D01*
G01X-115633Y739867D02*
X-119633D01*
G01X-105000Y734367D02*
X-105333Y734533D01*
Y734867D01*
X-105000Y735033D01*
X-104667Y734867D01*
Y734533D01*
X-105000Y734367D01*
G01Y738866D02*
X-105333Y739033D01*
Y739367D01*
X-105000Y739533D01*
X-104667Y739367D01*
Y739033D01*
X-105000Y738866D01*
G01X-82400Y744700D02*
Y734700D01*
G01X-86233Y744700D02*
X-78567D01*
G01X-74433Y734700D02*
Y744700D01*
X-70267D01*
X-68933Y744200D01*
X-68100Y743533D01*
X-67767Y742200D01*
X-68100Y740867D01*
X-69100Y740033D01*
X-70267Y739533D01*
X-74433D01*
G01X-70267D02*
X-67767Y734700D01*
G01X-63967D02*
X-59800Y744700D01*
X-55633Y734700D01*
G01X-57133Y738200D02*
X-62467D01*
G01X-52000Y734700D02*
X-45000Y744700D01*
G01X-52000D02*
X-45000Y734700D01*
G01X-35867Y740033D02*
X-35200Y740533D01*
X-34700Y741366D01*
X-34367Y742533D01*
X-34700Y743533D01*
X-35367Y744200D01*
X-36533Y744700D01*
X-41033D01*
Y734700D01*
X-35533D01*
X-34367Y735367D01*
X-33700Y736367D01*
X-33367Y737533D01*
X-33700Y738700D01*
X-34700Y739700D01*
X-35867Y740033D01*
X-41033D01*
G01X-30900Y731367D02*
X-20900D01*
G01X-10933Y743867D02*
X-11933Y744367D01*
X-13100Y744700D01*
X-14433D01*
X-15934Y744200D01*
X-17100Y743367D01*
X-17933Y742367D01*
X-18600Y740700D01*
X-18767Y739200D01*
X-18433Y737700D01*
X-17933Y736700D01*
X-16933Y735700D01*
X-15767Y735033D01*
X-14600Y734700D01*
X-13433D01*
X-12267Y735033D01*
X-11267Y735533D01*
X-10433Y736200D01*
G01X-6800Y734700D02*
X200Y744700D01*
G01X-6800D02*
X200Y734700D01*
G01X4333D02*
Y744700D01*
X7667D01*
X9000Y744200D01*
X10000Y743533D01*
X10833Y742533D01*
X11500Y741366D01*
X11667Y739700D01*
X11500Y738033D01*
X10833Y736867D01*
X10000Y735866D01*
X9000Y735200D01*
X7667Y734700D01*
X4333D01*
G01X-127767Y879300D02*
Y889300D01*
X-124433D01*
X-123100Y888800D01*
X-122100Y888133D01*
X-121267Y887133D01*
X-120600Y885966D01*
X-120433Y884300D01*
X-120600Y882633D01*
X-121267Y881467D01*
X-122100Y880466D01*
X-123100Y879800D01*
X-124433Y879300D01*
X-127767D01*
G01X-116067Y1000900D02*
X-122733D01*
Y1010900D01*
X-116067D01*
G01X-118733Y1006067D02*
X-122733D01*
G01X-111433Y1010900D02*
Y1000900D01*
X-104767D01*
G01X-100133Y1010900D02*
Y1000900D01*
X-93467D01*
G01X-87500Y1010900D02*
X-83500D01*
G01X-85500D02*
Y1000900D01*
G01X-87500D02*
X-83500D01*
G01X-77533D02*
Y1010900D01*
X-73533D01*
X-72200Y1010400D01*
X-71200Y1009233D01*
X-70867Y1007900D01*
X-71200Y1006567D01*
X-72033Y1005567D01*
X-73533Y1005066D01*
X-77533D01*
G01X-66400Y1002233D02*
X-65067Y1001400D01*
X-63567Y1000900D01*
X-62233D01*
X-60900Y1001400D01*
X-59900Y1002233D01*
X-59400Y1003400D01*
X-59733Y1004566D01*
X-60567Y1005567D01*
X-62067Y1006233D01*
X-64067Y1006567D01*
X-65233Y1007233D01*
X-65733Y1008400D01*
X-65400Y1009567D01*
X-64567Y1010400D01*
X-63400Y1010900D01*
X-62233D01*
X-61067Y1010567D01*
X-60067Y1009733D01*
G01X-48267Y1000900D02*
X-54933D01*
Y1010900D01*
X-48267D01*
G01X-50933Y1006067D02*
X-54933D01*
G01X-29000Y1010900D02*
Y1000900D01*
G01X-32833Y1010900D02*
X-25167D01*
G01X-20533Y1000900D02*
Y1010900D01*
G01Y1006067D02*
X-19700Y1006900D01*
X-18867Y1007400D01*
X-17533Y1007566D01*
X-16533Y1007400D01*
X-15367Y1006733D01*
X-14867Y1005733D01*
Y1000900D01*
G01X-8900Y1005400D02*
X-3567D01*
X-4067Y1006567D01*
X-4900Y1007233D01*
X-6067Y1007566D01*
X-7233Y1007400D01*
X-8233Y1006900D01*
X-8900Y1005733D01*
X-9233Y1004733D01*
Y1003733D01*
X-8900Y1002733D01*
X-8067Y1001733D01*
X-7067Y1001067D01*
X-5900Y1000900D01*
X-4733Y1001233D01*
X-3567Y1002233D01*
G01X2567Y1000900D02*
Y1007566D01*
G01Y1006233D02*
X3400Y1006900D01*
X4233Y1007400D01*
X5400Y1007566D01*
X6233Y1007400D01*
X7233Y1006900D01*
G01X11200Y1000900D02*
Y1007566D01*
G01Y1005733D02*
X11700Y1006567D01*
X12533Y1007233D01*
X13700Y1007566D01*
X14866Y1007233D01*
X15700Y1006567D01*
X16200Y1005733D01*
Y1000900D01*
G01Y1005733D02*
X16700Y1006567D01*
X17533Y1007233D01*
X18700Y1007566D01*
X19867Y1007233D01*
X20700Y1006567D01*
X21200Y1005567D01*
Y1000900D01*
G01X30500D02*
Y1007566D01*
G01Y1006400D02*
X29833Y1007067D01*
X28833Y1007400D01*
X27667Y1007566D01*
X26500Y1007233D01*
X25500Y1006567D01*
X24833Y1005567D01*
X24500Y1004233D01*
X24833Y1002900D01*
X25500Y1001900D01*
X26500Y1001233D01*
X27667Y1000900D01*
X28833Y1001067D01*
X29833Y1001567D01*
X30500Y1002233D01*
G01X38800Y1000900D02*
Y1010900D01*
G01X-160300Y1369600D02*
X-157967Y1359600D01*
X-155300Y1369600D01*
X-152633Y1359600D01*
X-150300Y1369600D01*
G01X-144000Y1366266D02*
Y1359600D01*
G01Y1368933D02*
X-144333Y1369100D01*
Y1369433D01*
X-144000Y1369600D01*
X-143667Y1369433D01*
Y1369100D01*
X-144000Y1368933D01*
G01X-135200Y1360766D02*
X-134367Y1360100D01*
X-133200Y1359600D01*
X-132200D01*
X-131200Y1359933D01*
X-130533Y1360433D01*
X-130200Y1361100D01*
X-130367Y1362100D01*
X-131033Y1362600D01*
X-134034Y1363600D01*
X-134700Y1364767D01*
X-134367Y1365600D01*
X-133700Y1366100D01*
X-132700Y1366266D01*
X-131700Y1366100D01*
X-130700Y1365600D01*
G01X-121400Y1369600D02*
Y1359600D01*
G01X-123733Y1366266D02*
X-119067D01*
G01X-112433Y1359600D02*
Y1366266D01*
G01Y1364933D02*
X-111600Y1365600D01*
X-110767Y1366100D01*
X-109600Y1366266D01*
X-108767Y1366100D01*
X-107767Y1365600D01*
G01X-98800Y1359600D02*
X-99800Y1359767D01*
X-100800Y1360433D01*
X-101467Y1361600D01*
X-101800Y1362933D01*
X-101467Y1364267D01*
X-100800Y1365433D01*
X-99800Y1366100D01*
X-98800Y1366266D01*
X-97800Y1366100D01*
X-96800Y1365433D01*
X-96133Y1364267D01*
X-95967Y1362933D01*
X-96133Y1361600D01*
X-96800Y1360433D01*
X-97800Y1359767D01*
X-98800Y1359600D01*
G01X-90333D02*
Y1366266D01*
G01Y1364600D02*
X-89667Y1365433D01*
X-88667Y1366100D01*
X-87333Y1366266D01*
X-86167Y1366100D01*
X-85167Y1365433D01*
X-84667Y1364267D01*
Y1359600D01*
G01X-64900Y1369600D02*
Y1359600D01*
G01X-68733Y1369600D02*
X-61067D01*
G01X-57100Y1359600D02*
Y1369600D01*
G01X-50100D02*
Y1359600D01*
G01Y1364600D02*
X-57100D01*
G01X-46633Y1359600D02*
Y1369600D01*
X-42300Y1361267D01*
X-37967Y1369600D01*
Y1359600D01*
G01X-34333Y1369600D02*
Y1359600D01*
X-27667D01*
G01X-5400Y1369600D02*
Y1359600D01*
G01Y1361100D02*
X-6067Y1360267D01*
X-7067Y1359767D01*
X-8233Y1359600D01*
X-9567Y1359933D01*
X-10567Y1360766D01*
X-11233Y1361767D01*
X-11400Y1362933D01*
X-11233Y1364100D01*
X-10567Y1365100D01*
X-9567Y1365933D01*
X-8233Y1366266D01*
X-7067Y1366100D01*
X-6233Y1365767D01*
X-5400Y1365100D01*
G01X400Y1364100D02*
X5733D01*
X5233Y1365267D01*
X4400Y1365933D01*
X3233Y1366266D01*
X2067Y1366100D01*
X1067Y1365600D01*
X400Y1364433D01*
X67Y1363433D01*
Y1362433D01*
X400Y1361433D01*
X1233Y1360433D01*
X2233Y1359767D01*
X3400Y1359600D01*
X4567Y1359933D01*
X5733Y1360933D01*
G01X13200Y1359600D02*
Y1368100D01*
X13533Y1368933D01*
X14200Y1369433D01*
X15200Y1369600D01*
X16200Y1369267D01*
X16700Y1368433D01*
G01X14700Y1365600D02*
X11367D01*
G01X28500Y1359600D02*
Y1366266D01*
G01Y1365100D02*
X27833Y1365767D01*
X26833Y1366100D01*
X25667Y1366266D01*
X24500Y1365933D01*
X23500Y1365267D01*
X22833Y1364267D01*
X22500Y1362933D01*
X22833Y1361600D01*
X23500Y1360600D01*
X24500Y1359933D01*
X25667Y1359600D01*
X26833Y1359767D01*
X27833Y1360267D01*
X28500Y1360933D01*
G01X33967Y1366266D02*
Y1361600D01*
X34633Y1360433D01*
X35633Y1359767D01*
X36800Y1359600D01*
X37967Y1359767D01*
X38967Y1360433D01*
X39633Y1361600D01*
G01Y1359600D02*
Y1366266D01*
G01X48100Y1359600D02*
Y1369600D01*
G01X59400D02*
Y1359600D01*
G01X57067Y1366266D02*
X61733D01*
G01X82000Y1369600D02*
Y1359600D01*
G01X79667Y1366266D02*
X84333D01*
G01X89800Y1356600D02*
X90800Y1356267D01*
X92133Y1356600D01*
X92967Y1357267D01*
X93633Y1358100D01*
X94633Y1360766D01*
X96800Y1366266D01*
G01X91467D02*
X94633Y1360766D01*
G01X101600Y1356267D02*
Y1366266D01*
G01Y1364767D02*
X102433Y1365600D01*
X103266Y1366100D01*
X104600Y1366266D01*
X105767Y1366100D01*
X106933Y1365267D01*
X107433Y1364100D01*
X107600Y1362933D01*
X107433Y1361767D01*
X106933Y1360600D01*
X105933Y1359933D01*
X104600Y1359600D01*
X103433Y1359767D01*
X102267Y1360267D01*
X101600Y1360933D01*
G01X113400Y1364100D02*
X118733D01*
X118233Y1365267D01*
X117400Y1365933D01*
X116233Y1366266D01*
X115067Y1366100D01*
X114067Y1365600D01*
X113400Y1364433D01*
X113067Y1363433D01*
Y1362433D01*
X113400Y1361433D01*
X114233Y1360433D01*
X115233Y1359767D01*
X116400Y1359600D01*
X117567Y1359933D01*
X118733Y1360933D01*
G01X-78967Y710600D02*
X-85633D01*
Y720600D01*
X-78967D01*
G01X-81633Y715767D02*
X-85633D01*
G01X-73167Y712433D02*
X-68833D01*
G01Y715433D02*
X-73167D01*
G01X-63367Y712100D02*
X-62367Y711267D01*
X-61200Y710767D01*
X-59700Y710600D01*
X-58200Y710933D01*
X-57033Y711600D01*
X-56200Y712767D01*
X-56033Y714100D01*
X-56367Y715433D01*
X-57200Y716267D01*
X-58367Y716933D01*
X-59533Y717100D01*
X-60700Y716933D01*
X-62200Y716267D01*
X-61700Y720600D01*
X-57200D01*
G01X-41433Y710600D02*
Y720600D01*
X-37100Y712267D01*
X-32767Y720600D01*
Y710600D01*
G01X-27800Y720600D02*
X-23800D01*
G01X-25800D02*
Y710600D01*
G01X-27800D02*
X-23800D01*
G01X-17833Y720600D02*
Y710600D01*
X-11167D01*
G01X-6700Y711933D02*
X-5367Y711100D01*
X-3867Y710600D01*
X-2533D01*
X-1200Y711100D01*
X-200Y711933D01*
X300Y713100D01*
X-33Y714266D01*
X-867Y715267D01*
X-2367Y715933D01*
X-4367Y716267D01*
X-5533Y716933D01*
X-6033Y718100D01*
X-5700Y719267D01*
X-4867Y720100D01*
X-3700Y720600D01*
X-2533D01*
X-1367Y720267D01*
X-367Y719433D01*
G01X18567Y707267D02*
X16900Y708933D01*
X16067Y710600D01*
Y717266D01*
X16900Y718933D01*
X18567Y720600D01*
G01X33700Y710600D02*
Y717266D01*
G01Y716100D02*
X33033Y716767D01*
X32033Y717100D01*
X30867Y717266D01*
X29700Y716933D01*
X28700Y716267D01*
X28033Y715267D01*
X27700Y713933D01*
X28033Y712600D01*
X28700Y711600D01*
X29700Y710933D01*
X30867Y710600D01*
X32033Y710767D01*
X33033Y711267D01*
X33700Y711933D01*
G01X42000Y710600D02*
Y720600D01*
G01X49133Y717266D02*
X51133Y710600D01*
X53300Y717266D01*
X55467Y710600D01*
X57467Y717266D01*
G01X67600Y710600D02*
Y717266D01*
G01Y716100D02*
X66933Y716767D01*
X65933Y717100D01*
X64767Y717266D01*
X63600Y716933D01*
X62600Y716267D01*
X61933Y715267D01*
X61600Y713933D01*
X61933Y712600D01*
X62600Y711600D01*
X63600Y710933D01*
X64767Y710600D01*
X65933Y710767D01*
X66933Y711267D01*
X67600Y711933D01*
G01X72400Y707600D02*
X73400Y707267D01*
X74733Y707600D01*
X75567Y708267D01*
X76233Y709100D01*
X77233Y711766D01*
X79400Y717266D01*
G01X74067D02*
X77233Y711766D01*
G01X84700D02*
X85533Y711100D01*
X86700Y710600D01*
X87700D01*
X88700Y710933D01*
X89367Y711433D01*
X89700Y712100D01*
X89533Y713100D01*
X88867Y713600D01*
X85866Y714600D01*
X85200Y715767D01*
X85533Y716600D01*
X86200Y717100D01*
X87200Y717266D01*
X88200Y717100D01*
X89200Y716600D01*
G01X106967Y710600D02*
Y720600D01*
G01X112300Y717266D02*
X106967Y713433D01*
G01X109133Y714933D02*
X112633Y710600D01*
G01X118600Y715100D02*
X123933D01*
X123433Y716267D01*
X122600Y716933D01*
X121433Y717266D01*
X120267Y717100D01*
X119267Y716600D01*
X118600Y715433D01*
X118267Y714433D01*
Y713433D01*
X118600Y712433D01*
X119433Y711433D01*
X120433Y710767D01*
X121600Y710600D01*
X122767Y710933D01*
X123933Y711933D01*
G01X129900Y715100D02*
X135233D01*
X134733Y716267D01*
X133900Y716933D01*
X132733Y717266D01*
X131567Y717100D01*
X130567Y716600D01*
X129900Y715433D01*
X129567Y714433D01*
Y713433D01*
X129900Y712433D01*
X130733Y711433D01*
X131733Y710767D01*
X132900Y710600D01*
X134067Y710933D01*
X135233Y711933D01*
G01X140700Y707267D02*
Y717266D01*
G01Y715767D02*
X141533Y716600D01*
X142366Y717100D01*
X143700Y717266D01*
X144867Y717100D01*
X146033Y716267D01*
X146533Y715100D01*
X146700Y713933D01*
X146533Y712767D01*
X146033Y711600D01*
X145033Y710933D01*
X143700Y710600D01*
X142533Y710767D01*
X141367Y711267D01*
X140700Y711933D01*
G01X162633Y712100D02*
X163633Y711267D01*
X164800Y710767D01*
X166300Y710600D01*
X167800Y710933D01*
X168967Y711600D01*
X169800Y712767D01*
X169967Y714100D01*
X169633Y715433D01*
X168800Y716267D01*
X167633Y716933D01*
X166467Y717100D01*
X165300Y716933D01*
X163800Y716267D01*
X164300Y720600D01*
X168800D01*
G01X183900Y710600D02*
Y717266D01*
G01Y715433D02*
X184400Y716267D01*
X185233Y716933D01*
X186400Y717266D01*
X187566Y716933D01*
X188400Y716267D01*
X188900Y715433D01*
Y710600D01*
G01Y715433D02*
X189400Y716267D01*
X190233Y716933D01*
X191400Y717266D01*
X192567Y716933D01*
X193400Y716267D01*
X193900Y715267D01*
Y710600D01*
G01X200200Y717266D02*
Y710600D01*
G01Y719933D02*
X199867Y720100D01*
Y720433D01*
X200200Y720600D01*
X200533Y720433D01*
Y720100D01*
X200200Y719933D01*
G01X211500Y710600D02*
Y720600D01*
G01X220300Y711766D02*
X221133Y711100D01*
X222300Y710600D01*
X223300D01*
X224300Y710933D01*
X224967Y711433D01*
X225300Y712100D01*
X225133Y713100D01*
X224467Y713600D01*
X221466Y714600D01*
X220800Y715767D01*
X221133Y716600D01*
X221800Y717100D01*
X222800Y717266D01*
X223800Y717100D01*
X224800Y716600D01*
G01X234933Y707267D02*
X236600Y708933D01*
X237433Y710600D01*
Y717266D01*
X236600Y718933D01*
X234933Y720600D01*
G01X-114467Y800300D02*
X-121133D01*
Y810300D01*
X-114467D01*
G01X-117133Y805467D02*
X-121133D01*
G01X-117600Y1242800D02*
X-113600D01*
G01X-115600D02*
Y1232800D01*
G01X-117600D02*
X-113600D01*
G01X-107133D02*
Y1239466D01*
G01Y1237800D02*
X-106467Y1238633D01*
X-105467Y1239300D01*
X-104133Y1239466D01*
X-102967Y1239300D01*
X-101967Y1238633D01*
X-101467Y1237467D01*
Y1232800D01*
G01X-95833D02*
Y1239466D01*
G01Y1237800D02*
X-95167Y1238633D01*
X-94167Y1239300D01*
X-92833Y1239466D01*
X-91667Y1239300D01*
X-90667Y1238633D01*
X-90167Y1237467D01*
Y1232800D01*
G01X-84200Y1237300D02*
X-78867D01*
X-79367Y1238467D01*
X-80200Y1239133D01*
X-81367Y1239466D01*
X-82533Y1239300D01*
X-83533Y1238800D01*
X-84200Y1237633D01*
X-84533Y1236633D01*
Y1235633D01*
X-84200Y1234633D01*
X-83367Y1233633D01*
X-82367Y1232967D01*
X-81200Y1232800D01*
X-80033Y1233133D01*
X-78867Y1234133D01*
G01X-72733Y1232800D02*
Y1239466D01*
G01Y1238133D02*
X-71900Y1238800D01*
X-71067Y1239300D01*
X-69900Y1239466D01*
X-69067Y1239300D01*
X-68067Y1238800D01*
G01X-51467Y1232800D02*
Y1242800D01*
X-48133D01*
X-46800Y1242300D01*
X-45800Y1241633D01*
X-44967Y1240633D01*
X-44300Y1239466D01*
X-44133Y1237800D01*
X-44300Y1236133D01*
X-44967Y1234967D01*
X-45800Y1233966D01*
X-46800Y1233300D01*
X-48133Y1232800D01*
X-51467D01*
G01X-36500Y1239466D02*
Y1232800D01*
G01Y1242133D02*
X-36833Y1242300D01*
Y1242633D01*
X-36500Y1242800D01*
X-36167Y1242633D01*
Y1242300D01*
X-36500Y1242133D01*
G01X-22200Y1232800D02*
Y1239466D01*
G01Y1238300D02*
X-22867Y1238967D01*
X-23867Y1239300D01*
X-25033Y1239466D01*
X-26200Y1239133D01*
X-27200Y1238467D01*
X-27867Y1237467D01*
X-28200Y1236133D01*
X-27867Y1234800D01*
X-27200Y1233800D01*
X-26200Y1233133D01*
X-25033Y1232800D01*
X-23867Y1232967D01*
X-22867Y1233467D01*
X-22200Y1234133D01*
G01X-18900Y1232800D02*
Y1239466D01*
G01Y1237633D02*
X-18400Y1238467D01*
X-17567Y1239133D01*
X-16400Y1239466D01*
X-15234Y1239133D01*
X-14400Y1238467D01*
X-13900Y1237633D01*
Y1232800D01*
G01Y1237633D02*
X-13400Y1238467D01*
X-12567Y1239133D01*
X-11400Y1239466D01*
X-10233Y1239133D01*
X-9400Y1238467D01*
X-8900Y1237467D01*
Y1232800D01*
G01X-5100Y1237300D02*
X233D01*
X-267Y1238467D01*
X-1100Y1239133D01*
X-2267Y1239466D01*
X-3433Y1239300D01*
X-4433Y1238800D01*
X-5100Y1237633D01*
X-5433Y1236633D01*
Y1235633D01*
X-5100Y1234633D01*
X-4267Y1233633D01*
X-3267Y1232967D01*
X-2100Y1232800D01*
X-933Y1233133D01*
X233Y1234133D01*
G01X8700Y1242800D02*
Y1232800D01*
G01X6367Y1239466D02*
X11033D01*
G01X17500Y1237300D02*
X22833D01*
X22333Y1238467D01*
X21500Y1239133D01*
X20333Y1239466D01*
X19167Y1239300D01*
X18167Y1238800D01*
X17500Y1237633D01*
X17167Y1236633D01*
Y1235633D01*
X17500Y1234633D01*
X18333Y1233633D01*
X19333Y1232967D01*
X20500Y1232800D01*
X21667Y1233133D01*
X22833Y1234133D01*
G01X28967Y1232800D02*
Y1239466D01*
G01Y1238133D02*
X29800Y1238800D01*
X30633Y1239300D01*
X31800Y1239466D01*
X32633Y1239300D01*
X33633Y1238800D01*
G01X-46233Y782967D02*
X-47233Y783467D01*
X-48400Y783800D01*
X-49733D01*
X-51234Y783300D01*
X-52400Y782467D01*
X-53233Y781467D01*
X-53900Y779800D01*
X-54067Y778300D01*
X-53733Y776800D01*
X-53233Y775800D01*
X-52233Y774800D01*
X-51067Y774133D01*
X-49900Y773800D01*
X-48733D01*
X-47567Y774133D01*
X-46567Y774633D01*
X-45733Y775300D01*
G01X-54367Y971400D02*
X-50200Y981400D01*
X-46033Y971400D01*
G01X-47533Y974900D02*
X-52867D01*
G01X-22810Y1290280D02*
X-19477D01*
Y1287280D01*
X-20477Y1286280D01*
X-21643Y1285613D01*
X-23310Y1285280D01*
X-24977Y1285613D01*
X-26143Y1286280D01*
X-27143Y1287280D01*
X-27810Y1288447D01*
X-28143Y1289780D01*
Y1290947D01*
X-27810Y1291946D01*
X-27143Y1293113D01*
X-26143Y1294113D01*
X-25144Y1294780D01*
X-23810Y1295280D01*
X-22643D01*
X-21310Y1294947D01*
X-20310Y1294280D01*
G01X-9510Y1285280D02*
Y1291946D01*
G01Y1290780D02*
X-10177Y1291447D01*
X-11177Y1291780D01*
X-12343Y1291946D01*
X-13510Y1291613D01*
X-14510Y1290947D01*
X-15177Y1289947D01*
X-15510Y1288613D01*
X-15177Y1287280D01*
X-14510Y1286280D01*
X-13510Y1285613D01*
X-12343Y1285280D01*
X-11177Y1285447D01*
X-10177Y1285947D01*
X-9510Y1286613D01*
G01X-4210Y1281947D02*
Y1291946D01*
G01Y1290447D02*
X-3377Y1291280D01*
X-2544Y1291780D01*
X-1210Y1291946D01*
X-43Y1291780D01*
X1123Y1290947D01*
X1623Y1289780D01*
X1790Y1288613D01*
X1623Y1287447D01*
X1123Y1286280D01*
X123Y1285613D01*
X-1210Y1285280D01*
X-2377Y1285447D01*
X-3543Y1285947D01*
X-4210Y1286613D01*
G01X16390Y1295280D02*
X18723Y1285280D01*
X21390Y1295280D01*
X24057Y1285280D01*
X26390Y1295280D01*
G01X32690Y1291946D02*
Y1285280D01*
G01Y1294613D02*
X32357Y1294780D01*
Y1295113D01*
X32690Y1295280D01*
X33023Y1295113D01*
Y1294780D01*
X32690Y1294613D01*
G01X46990Y1295280D02*
Y1285280D01*
G01Y1286780D02*
X46323Y1285947D01*
X45323Y1285447D01*
X44157Y1285280D01*
X42823Y1285613D01*
X41823Y1286446D01*
X41157Y1287447D01*
X40990Y1288613D01*
X41157Y1289780D01*
X41823Y1290780D01*
X42823Y1291613D01*
X44157Y1291946D01*
X45323Y1291780D01*
X46157Y1291447D01*
X46990Y1290780D01*
G01X55290Y1295280D02*
Y1285280D01*
G01X52957Y1291946D02*
X57623D01*
G01X63757Y1285280D02*
Y1295280D01*
G01Y1290447D02*
X64590Y1291280D01*
X65423Y1291780D01*
X66757Y1291946D01*
X67757Y1291780D01*
X68923Y1291113D01*
X69423Y1290113D01*
Y1285280D01*
G01X-20370Y1333880D02*
X-21704Y1334047D01*
X-22870Y1334713D01*
X-23870Y1335713D01*
X-24537Y1336880D01*
X-24870Y1338213D01*
Y1339547D01*
X-24537Y1340880D01*
X-23870Y1342047D01*
X-22870Y1343047D01*
X-21704Y1343713D01*
X-20370Y1343880D01*
X-19037Y1343713D01*
X-17870Y1343047D01*
X-16870Y1342047D01*
X-16203Y1340880D01*
X-15870Y1339547D01*
Y1338213D01*
X-16203Y1336880D01*
X-16870Y1335713D01*
X-17870Y1334713D01*
X-19037Y1334047D01*
X-20370Y1333880D01*
G01X-11903Y1340546D02*
Y1335880D01*
X-11237Y1334713D01*
X-10237Y1334047D01*
X-9070Y1333880D01*
X-7903Y1334047D01*
X-6903Y1334713D01*
X-6237Y1335880D01*
G01Y1333880D02*
Y1340546D01*
G01X2230Y1343880D02*
Y1333880D01*
G01X-103Y1340546D02*
X4563D01*
G01X11030Y1338380D02*
X16363D01*
X15863Y1339547D01*
X15030Y1340213D01*
X13863Y1340546D01*
X12697Y1340380D01*
X11697Y1339880D01*
X11030Y1338713D01*
X10697Y1337713D01*
Y1336713D01*
X11030Y1335713D01*
X11863Y1334713D01*
X12863Y1334047D01*
X14030Y1333880D01*
X15197Y1334213D01*
X16363Y1335213D01*
G01X22497Y1333880D02*
Y1340546D01*
G01Y1339213D02*
X23330Y1339880D01*
X24163Y1340380D01*
X25330Y1340546D01*
X26163Y1340380D01*
X27163Y1339880D01*
G01X43763Y1333880D02*
Y1343880D01*
X47097D01*
X48430Y1343380D01*
X49430Y1342713D01*
X50263Y1341713D01*
X50930Y1340546D01*
X51097Y1338880D01*
X50930Y1337213D01*
X50263Y1336047D01*
X49430Y1335046D01*
X48430Y1334380D01*
X47097Y1333880D01*
X43763D01*
G01X58730Y1340546D02*
Y1333880D01*
G01Y1343213D02*
X58397Y1343380D01*
Y1343713D01*
X58730Y1343880D01*
X59063Y1343713D01*
Y1343380D01*
X58730Y1343213D01*
G01X73030Y1333880D02*
Y1340546D01*
G01Y1339380D02*
X72363Y1340047D01*
X71363Y1340380D01*
X70197Y1340546D01*
X69030Y1340213D01*
X68030Y1339547D01*
X67363Y1338547D01*
X67030Y1337213D01*
X67363Y1335880D01*
X68030Y1334880D01*
X69030Y1334213D01*
X70197Y1333880D01*
X71363Y1334047D01*
X72363Y1334547D01*
X73030Y1335213D01*
G01X76330Y1333880D02*
Y1340546D01*
G01Y1338713D02*
X76830Y1339547D01*
X77663Y1340213D01*
X78830Y1340546D01*
X79996Y1340213D01*
X80830Y1339547D01*
X81330Y1338713D01*
Y1333880D01*
G01Y1338713D02*
X81830Y1339547D01*
X82663Y1340213D01*
X83830Y1340546D01*
X84997Y1340213D01*
X85830Y1339547D01*
X86330Y1338547D01*
Y1333880D01*
G01X90130Y1338380D02*
X95463D01*
X94963Y1339547D01*
X94130Y1340213D01*
X92963Y1340546D01*
X91797Y1340380D01*
X90797Y1339880D01*
X90130Y1338713D01*
X89797Y1337713D01*
Y1336713D01*
X90130Y1335713D01*
X90963Y1334713D01*
X91963Y1334047D01*
X93130Y1333880D01*
X94297Y1334213D01*
X95463Y1335213D01*
G01X103930Y1343880D02*
Y1333880D01*
G01X101597Y1340546D02*
X106263D01*
G01X112730Y1338380D02*
X118063D01*
X117563Y1339547D01*
X116730Y1340213D01*
X115563Y1340546D01*
X114397Y1340380D01*
X113397Y1339880D01*
X112730Y1338713D01*
X112397Y1337713D01*
Y1336713D01*
X112730Y1335713D01*
X113563Y1334713D01*
X114563Y1334047D01*
X115730Y1333880D01*
X116897Y1334213D01*
X118063Y1335213D01*
G01X124197Y1333880D02*
Y1340546D01*
G01Y1339213D02*
X125030Y1339880D01*
X125863Y1340380D01*
X127030Y1340546D01*
X127863Y1340380D01*
X128863Y1339880D01*
G01X18733Y885133D02*
X19400Y885633D01*
X19900Y886466D01*
X20233Y887633D01*
X19900Y888633D01*
X19233Y889300D01*
X18067Y889800D01*
X13567D01*
Y879800D01*
X19067D01*
X20233Y880467D01*
X20900Y881467D01*
X21233Y882633D01*
X20900Y883800D01*
X19900Y884800D01*
X18733Y885133D01*
X13567D01*
G01X47700Y1150600D02*
X51033D01*
Y1147600D01*
X50033Y1146600D01*
X48867Y1145933D01*
X47200Y1145600D01*
X45533Y1145933D01*
X44367Y1146600D01*
X43367Y1147600D01*
X42700Y1148767D01*
X42367Y1150100D01*
Y1151267D01*
X42700Y1152266D01*
X43367Y1153433D01*
X44367Y1154433D01*
X45366Y1155100D01*
X46700Y1155600D01*
X47867D01*
X49200Y1155267D01*
X50200Y1154600D01*
G01X61000Y1145600D02*
Y1152266D01*
G01Y1151100D02*
X60333Y1151767D01*
X59333Y1152100D01*
X58167Y1152266D01*
X57000Y1151933D01*
X56000Y1151267D01*
X55333Y1150267D01*
X55000Y1148933D01*
X55333Y1147600D01*
X56000Y1146600D01*
X57000Y1145933D01*
X58167Y1145600D01*
X59333Y1145767D01*
X60333Y1146267D01*
X61000Y1146933D01*
G01X66300Y1142267D02*
Y1152266D01*
G01Y1150767D02*
X67133Y1151600D01*
X67966Y1152100D01*
X69300Y1152266D01*
X70467Y1152100D01*
X71633Y1151267D01*
X72133Y1150100D01*
X72300Y1148933D01*
X72133Y1147767D01*
X71633Y1146600D01*
X70633Y1145933D01*
X69300Y1145600D01*
X68133Y1145767D01*
X66967Y1146267D01*
X66300Y1146933D01*
G01X86900Y1155600D02*
X89233Y1145600D01*
X91900Y1155600D01*
X94567Y1145600D01*
X96900Y1155600D01*
G01X103200Y1152266D02*
Y1145600D01*
G01Y1154933D02*
X102867Y1155100D01*
Y1155433D01*
X103200Y1155600D01*
X103533Y1155433D01*
Y1155100D01*
X103200Y1154933D01*
G01X117500Y1155600D02*
Y1145600D01*
G01Y1147100D02*
X116833Y1146267D01*
X115833Y1145767D01*
X114667Y1145600D01*
X113333Y1145933D01*
X112333Y1146766D01*
X111667Y1147767D01*
X111500Y1148933D01*
X111667Y1150100D01*
X112333Y1151100D01*
X113333Y1151933D01*
X114667Y1152266D01*
X115833Y1152100D01*
X116667Y1151767D01*
X117500Y1151100D01*
G01X125800Y1155600D02*
Y1145600D01*
G01X123467Y1152266D02*
X128133D01*
G01X134267Y1145600D02*
Y1155600D01*
G01Y1150767D02*
X135100Y1151600D01*
X135933Y1152100D01*
X137267Y1152266D01*
X138267Y1152100D01*
X139433Y1151433D01*
X139933Y1150433D01*
Y1145600D01*
G01X146233Y1147433D02*
X150567D01*
G01Y1150433D02*
X146233D01*
G01X156033Y1147600D02*
X157033Y1146433D01*
X158366Y1145767D01*
X159867Y1145600D01*
X161200Y1145767D01*
X162533Y1146600D01*
X163367Y1147600D01*
X163533Y1148600D01*
X163200Y1149766D01*
X162033Y1150600D01*
X160867Y1150933D01*
X159367D01*
G01X160867D02*
X161867Y1151433D01*
X162700Y1152266D01*
X163033Y1153267D01*
X162700Y1154267D01*
X161867Y1155100D01*
X160367Y1155600D01*
X158867Y1155433D01*
X157367Y1154767D01*
G01X171000Y1155600D02*
X169666Y1155267D01*
X168667Y1154433D01*
X168000Y1153433D01*
X167500Y1152100D01*
X167333Y1150600D01*
X167500Y1149100D01*
X168000Y1147767D01*
X168667Y1146766D01*
X169666Y1145933D01*
X171000Y1145600D01*
X172333Y1145933D01*
X173333Y1146766D01*
X174000Y1147767D01*
X174500Y1149100D01*
X174667Y1150600D01*
X174500Y1152100D01*
X174000Y1153433D01*
X173333Y1154433D01*
X172333Y1155267D01*
X171000Y1155600D01*
G01X44867Y1161600D02*
Y1171600D01*
X52533Y1161600D01*
Y1171600D01*
G01X57167Y1168266D02*
Y1163600D01*
X57833Y1162433D01*
X58833Y1161767D01*
X60000Y1161600D01*
X61167Y1161767D01*
X62167Y1162433D01*
X62833Y1163600D01*
G01Y1161600D02*
Y1168266D01*
G01X66300Y1161600D02*
Y1168266D01*
G01Y1166433D02*
X66800Y1167267D01*
X67633Y1167933D01*
X68800Y1168266D01*
X69966Y1167933D01*
X70800Y1167267D01*
X71300Y1166433D01*
Y1161600D01*
G01Y1166433D02*
X71800Y1167267D01*
X72633Y1167933D01*
X73800Y1168266D01*
X74967Y1167933D01*
X75800Y1167267D01*
X76300Y1166267D01*
Y1161600D01*
G01X90400Y1162933D02*
X91733Y1162100D01*
X93233Y1161600D01*
X94567D01*
X95900Y1162100D01*
X96900Y1162933D01*
X97400Y1164100D01*
X97067Y1165266D01*
X96233Y1166267D01*
X94733Y1166933D01*
X92733Y1167267D01*
X91567Y1167933D01*
X91067Y1169100D01*
X91400Y1170267D01*
X92233Y1171100D01*
X93400Y1171600D01*
X94567D01*
X95733Y1171267D01*
X96733Y1170433D01*
G01X102200Y1158267D02*
Y1168266D01*
G01Y1166767D02*
X103033Y1167600D01*
X103866Y1168100D01*
X105200Y1168266D01*
X106367Y1168100D01*
X107533Y1167267D01*
X108033Y1166100D01*
X108200Y1164933D01*
X108033Y1163767D01*
X107533Y1162600D01*
X106533Y1161933D01*
X105200Y1161600D01*
X104033Y1161767D01*
X102867Y1162267D01*
X102200Y1162933D01*
G01X116500Y1161600D02*
X115500Y1161767D01*
X114500Y1162433D01*
X113833Y1163600D01*
X113500Y1164933D01*
X113833Y1166267D01*
X114500Y1167433D01*
X115500Y1168100D01*
X116500Y1168266D01*
X117500Y1168100D01*
X118500Y1167433D01*
X119167Y1166267D01*
X119333Y1164933D01*
X119167Y1163600D01*
X118500Y1162433D01*
X117500Y1161767D01*
X116500Y1161600D01*
G01X124967D02*
Y1171600D01*
G01X130300Y1168266D02*
X124967Y1164433D01*
G01X127133Y1165933D02*
X130633Y1161600D01*
G01X136600Y1166100D02*
X141933D01*
X141433Y1167267D01*
X140600Y1167933D01*
X139433Y1168266D01*
X138267Y1168100D01*
X137267Y1167600D01*
X136600Y1166433D01*
X136267Y1165433D01*
Y1164433D01*
X136600Y1163433D01*
X137433Y1162433D01*
X138433Y1161767D01*
X139600Y1161600D01*
X140767Y1161933D01*
X141933Y1162933D01*
G01X147900Y1162766D02*
X148733Y1162100D01*
X149900Y1161600D01*
X150900D01*
X151900Y1161933D01*
X152567Y1162433D01*
X152900Y1163100D01*
X152733Y1164100D01*
X152067Y1164600D01*
X149066Y1165600D01*
X148400Y1166767D01*
X148733Y1167600D01*
X149400Y1168100D01*
X150400Y1168266D01*
X151400Y1168100D01*
X152400Y1167600D01*
G01X159533Y1163433D02*
X163867D01*
G01Y1166433D02*
X159533D01*
G01X175000Y1161600D02*
Y1171600D01*
X168833Y1164433D01*
X177167D01*
G01X46700Y1181600D02*
X45366Y1181767D01*
X44200Y1182433D01*
X43200Y1183433D01*
X42533Y1184600D01*
X42200Y1185933D01*
Y1187267D01*
X42533Y1188600D01*
X43200Y1189767D01*
X44200Y1190767D01*
X45366Y1191433D01*
X46700Y1191600D01*
X48033Y1191433D01*
X49200Y1190767D01*
X50200Y1189767D01*
X50867Y1188600D01*
X51200Y1187267D01*
Y1185933D01*
X50867Y1184600D01*
X50200Y1183433D01*
X49200Y1182433D01*
X48033Y1181767D01*
X46700Y1181600D01*
G01X55167Y1188266D02*
Y1183600D01*
X55833Y1182433D01*
X56833Y1181767D01*
X58000Y1181600D01*
X59167Y1181767D01*
X60167Y1182433D01*
X60833Y1183600D01*
G01Y1181600D02*
Y1188266D01*
G01X69300Y1191600D02*
Y1181600D01*
G01X66967Y1188266D02*
X71633D01*
G01X78100Y1186100D02*
X83433D01*
X82933Y1187267D01*
X82100Y1187933D01*
X80933Y1188266D01*
X79767Y1188100D01*
X78767Y1187600D01*
X78100Y1186433D01*
X77767Y1185433D01*
Y1184433D01*
X78100Y1183433D01*
X78933Y1182433D01*
X79933Y1181767D01*
X81100Y1181600D01*
X82267Y1181933D01*
X83433Y1182933D01*
G01X89567Y1181600D02*
Y1188266D01*
G01Y1186933D02*
X90400Y1187600D01*
X91233Y1188100D01*
X92400Y1188266D01*
X93233Y1188100D01*
X94233Y1187600D01*
G01X110833Y1181600D02*
Y1191600D01*
X114167D01*
X115500Y1191100D01*
X116500Y1190433D01*
X117333Y1189433D01*
X118000Y1188266D01*
X118167Y1186600D01*
X118000Y1184933D01*
X117333Y1183767D01*
X116500Y1182766D01*
X115500Y1182100D01*
X114167Y1181600D01*
X110833D01*
G01X125800Y1188266D02*
Y1181600D01*
G01Y1190933D02*
X125467Y1191100D01*
Y1191433D01*
X125800Y1191600D01*
X126133Y1191433D01*
Y1191100D01*
X125800Y1190933D01*
G01X140100Y1181600D02*
Y1188266D01*
G01Y1187100D02*
X139433Y1187767D01*
X138433Y1188100D01*
X137267Y1188266D01*
X136100Y1187933D01*
X135100Y1187267D01*
X134433Y1186267D01*
X134100Y1184933D01*
X134433Y1183600D01*
X135100Y1182600D01*
X136100Y1181933D01*
X137267Y1181600D01*
X138433Y1181767D01*
X139433Y1182267D01*
X140100Y1182933D01*
G01X143400Y1181600D02*
Y1188266D01*
G01Y1186433D02*
X143900Y1187267D01*
X144733Y1187933D01*
X145900Y1188266D01*
X147066Y1187933D01*
X147900Y1187267D01*
X148400Y1186433D01*
Y1181600D01*
G01Y1186433D02*
X148900Y1187267D01*
X149733Y1187933D01*
X150900Y1188266D01*
X152067Y1187933D01*
X152900Y1187267D01*
X153400Y1186267D01*
Y1181600D01*
G01X157200Y1186100D02*
X162533D01*
X162033Y1187267D01*
X161200Y1187933D01*
X160033Y1188266D01*
X158867Y1188100D01*
X157867Y1187600D01*
X157200Y1186433D01*
X156867Y1185433D01*
Y1184433D01*
X157200Y1183433D01*
X158033Y1182433D01*
X159033Y1181767D01*
X160200Y1181600D01*
X161367Y1181933D01*
X162533Y1182933D01*
G01X171000Y1191600D02*
Y1181600D01*
G01X168667Y1188266D02*
X173333D01*
G01X179800Y1186100D02*
X185133D01*
X184633Y1187267D01*
X183800Y1187933D01*
X182633Y1188266D01*
X181467Y1188100D01*
X180467Y1187600D01*
X179800Y1186433D01*
X179467Y1185433D01*
Y1184433D01*
X179800Y1183433D01*
X180633Y1182433D01*
X181633Y1181767D01*
X182800Y1181600D01*
X183967Y1181933D01*
X185133Y1182933D01*
G01X191267Y1181600D02*
Y1188266D01*
G01Y1186933D02*
X192100Y1187600D01*
X192933Y1188100D01*
X194100Y1188266D01*
X194933Y1188100D01*
X195933Y1187600D01*
G01X202733Y1183433D02*
X207067D01*
G01Y1186433D02*
X202733D01*
G01X216200Y1181600D02*
Y1191600D01*
X214200Y1189600D01*
G01Y1181600D02*
X218200D01*
G01X227500Y1191600D02*
X226166Y1191267D01*
X225167Y1190433D01*
X224500Y1189433D01*
X224000Y1188100D01*
X223833Y1186600D01*
X224000Y1185100D01*
X224500Y1183767D01*
X225167Y1182766D01*
X226166Y1181933D01*
X227500Y1181600D01*
X228833Y1181933D01*
X229833Y1182766D01*
X230500Y1183767D01*
X231000Y1185100D01*
X231167Y1186600D01*
X231000Y1188100D01*
X230500Y1189433D01*
X229833Y1190433D01*
X228833Y1191267D01*
X227500Y1191600D01*
G01X235133Y1183600D02*
X236133Y1182433D01*
X237466Y1181767D01*
X238967Y1181600D01*
X240300Y1181767D01*
X241633Y1182600D01*
X242467Y1183600D01*
X242633Y1184600D01*
X242300Y1185766D01*
X241133Y1186600D01*
X239967Y1186933D01*
X238467D01*
G01X239967D02*
X240967Y1187433D01*
X241800Y1188266D01*
X242133Y1189267D01*
X241800Y1190267D01*
X240967Y1191100D01*
X239467Y1191600D01*
X237967Y1191433D01*
X236467Y1190767D01*
G01X42700Y1213600D02*
X46700D01*
G01X44700D02*
Y1203600D01*
G01X42700D02*
X46700D01*
G01X53167D02*
Y1210266D01*
G01Y1208600D02*
X53833Y1209433D01*
X54833Y1210100D01*
X56167Y1210266D01*
X57333Y1210100D01*
X58333Y1209433D01*
X58833Y1208267D01*
Y1203600D01*
G01X64467D02*
Y1210266D01*
G01Y1208600D02*
X65133Y1209433D01*
X66133Y1210100D01*
X67467Y1210266D01*
X68633Y1210100D01*
X69633Y1209433D01*
X70133Y1208267D01*
Y1203600D01*
G01X76100Y1208100D02*
X81433D01*
X80933Y1209267D01*
X80100Y1209933D01*
X78933Y1210266D01*
X77767Y1210100D01*
X76767Y1209600D01*
X76100Y1208433D01*
X75767Y1207433D01*
Y1206433D01*
X76100Y1205433D01*
X76933Y1204433D01*
X77933Y1203767D01*
X79100Y1203600D01*
X80267Y1203933D01*
X81433Y1204933D01*
G01X87567Y1203600D02*
Y1210266D01*
G01Y1208933D02*
X88400Y1209600D01*
X89233Y1210100D01*
X90400Y1210266D01*
X91233Y1210100D01*
X92233Y1209600D01*
G01X108833Y1203600D02*
Y1213600D01*
X112167D01*
X113500Y1213100D01*
X114500Y1212433D01*
X115333Y1211433D01*
X116000Y1210266D01*
X116167Y1208600D01*
X116000Y1206933D01*
X115333Y1205767D01*
X114500Y1204766D01*
X113500Y1204100D01*
X112167Y1203600D01*
X108833D01*
G01X123800Y1210266D02*
Y1203600D01*
G01Y1212933D02*
X123467Y1213100D01*
Y1213433D01*
X123800Y1213600D01*
X124133Y1213433D01*
Y1213100D01*
X123800Y1212933D01*
G01X138100Y1203600D02*
Y1210266D01*
G01Y1209100D02*
X137433Y1209767D01*
X136433Y1210100D01*
X135267Y1210266D01*
X134100Y1209933D01*
X133100Y1209267D01*
X132433Y1208267D01*
X132100Y1206933D01*
X132433Y1205600D01*
X133100Y1204600D01*
X134100Y1203933D01*
X135267Y1203600D01*
X136433Y1203767D01*
X137433Y1204267D01*
X138100Y1204933D01*
G01X141400Y1203600D02*
Y1210266D01*
G01Y1208433D02*
X141900Y1209267D01*
X142733Y1209933D01*
X143900Y1210266D01*
X145066Y1209933D01*
X145900Y1209267D01*
X146400Y1208433D01*
Y1203600D01*
G01Y1208433D02*
X146900Y1209267D01*
X147733Y1209933D01*
X148900Y1210266D01*
X150067Y1209933D01*
X150900Y1209267D01*
X151400Y1208267D01*
Y1203600D01*
G01X155200Y1208100D02*
X160533D01*
X160033Y1209267D01*
X159200Y1209933D01*
X158033Y1210266D01*
X156867Y1210100D01*
X155867Y1209600D01*
X155200Y1208433D01*
X154867Y1207433D01*
Y1206433D01*
X155200Y1205433D01*
X156033Y1204433D01*
X157033Y1203767D01*
X158200Y1203600D01*
X159367Y1203933D01*
X160533Y1204933D01*
G01X169000Y1213600D02*
Y1203600D01*
G01X166667Y1210266D02*
X171333D01*
G01X177800Y1208100D02*
X183133D01*
X182633Y1209267D01*
X181800Y1209933D01*
X180633Y1210266D01*
X179467Y1210100D01*
X178467Y1209600D01*
X177800Y1208433D01*
X177467Y1207433D01*
Y1206433D01*
X177800Y1205433D01*
X178633Y1204433D01*
X179633Y1203767D01*
X180800Y1203600D01*
X181967Y1203933D01*
X183133Y1204933D01*
G01X189267Y1203600D02*
Y1210266D01*
G01Y1208933D02*
X190100Y1209600D01*
X190933Y1210100D01*
X192100Y1210266D01*
X192933Y1210100D01*
X193933Y1209600D01*
G01X200733Y1205433D02*
X205067D01*
G01Y1208433D02*
X200733D01*
G01X211367Y1204766D02*
X212533Y1203933D01*
X213867Y1203600D01*
X215200Y1203933D01*
X216367Y1204933D01*
X217200Y1206433D01*
X217533Y1207933D01*
Y1209767D01*
X217200Y1211267D01*
X216367Y1212600D01*
X215367Y1213267D01*
X214200Y1213600D01*
X212866Y1213267D01*
X211867Y1212600D01*
X211200Y1211600D01*
X210867Y1210266D01*
X211200Y1209100D01*
X212033Y1207933D01*
X213033Y1207266D01*
X214200Y1207100D01*
X215533Y1207433D01*
X216533Y1208267D01*
X217533Y1209767D01*
G01X221833Y1205600D02*
X222833Y1204433D01*
X224166Y1203767D01*
X225667Y1203600D01*
X227000Y1203767D01*
X228333Y1204600D01*
X229167Y1205600D01*
X229333Y1206600D01*
X229000Y1207766D01*
X227833Y1208600D01*
X226667Y1208933D01*
X225167D01*
G01X226667D02*
X227667Y1209433D01*
X228500Y1210266D01*
X228833Y1211267D01*
X228500Y1212267D01*
X227667Y1213100D01*
X226167Y1213600D01*
X224667Y1213433D01*
X223167Y1212767D01*
G54D12*
G01X355441Y659700D02*
Y667275D01*
X359040D01*
G01X357714Y663614D02*
X355441D01*
G01X364815Y659700D02*
X364247Y659826D01*
X363679Y660331D01*
X363300Y661215D01*
X363111Y662225D01*
X363300Y663235D01*
X363679Y664119D01*
X364247Y664624D01*
X364815Y664750D01*
X365384Y664624D01*
X365952Y664119D01*
X366330Y663235D01*
X366425Y662225D01*
X366330Y661215D01*
X365952Y660331D01*
X365384Y659826D01*
X364815Y659700D01*
G01X371065D02*
Y664750D01*
G01Y663740D02*
X371538Y664245D01*
X372012Y664624D01*
X372675Y664750D01*
X373148Y664624D01*
X373716Y664245D01*
G01X386120Y663109D02*
X389150D01*
X388866Y663993D01*
X388393Y664497D01*
X387730Y664750D01*
X387067Y664624D01*
X386499Y664245D01*
X386120Y663361D01*
X385931Y662604D01*
Y661846D01*
X386120Y661089D01*
X386594Y660331D01*
X387162Y659826D01*
X387825Y659700D01*
X388487Y659952D01*
X389150Y660710D01*
G01X393695Y664750D02*
X396536Y659700D01*
G01Y664750D02*
X393695Y659700D01*
G01X404395D02*
Y664750D01*
G01Y663866D02*
X404016Y664371D01*
X403448Y664624D01*
X402785Y664750D01*
X402122Y664497D01*
X401554Y663993D01*
X401175Y663235D01*
X400986Y662225D01*
X401175Y661215D01*
X401554Y660457D01*
X402122Y659952D01*
X402785Y659700D01*
X403448Y659826D01*
X404016Y660205D01*
X404395Y660710D01*
G01X407425Y659700D02*
Y664750D01*
G01Y663361D02*
X407709Y663993D01*
X408182Y664497D01*
X408845Y664750D01*
X409508Y664497D01*
X409981Y663993D01*
X410265Y663361D01*
Y659700D01*
G01Y663361D02*
X410550Y663993D01*
X411023Y664497D01*
X411686Y664750D01*
X412349Y664497D01*
X412822Y663993D01*
X413106Y663235D01*
Y659700D01*
G01X416136Y657175D02*
Y664750D01*
G01Y663614D02*
X416610Y664245D01*
X417083Y664624D01*
X417840Y664750D01*
X418503Y664624D01*
X419166Y663993D01*
X419450Y663109D01*
X419545Y662225D01*
X419450Y661341D01*
X419166Y660457D01*
X418598Y659952D01*
X417840Y659700D01*
X417178Y659826D01*
X416515Y660205D01*
X416136Y660710D01*
G01X425415Y659700D02*
Y667275D01*
G01X431570Y663109D02*
X434600D01*
X434316Y663993D01*
X433843Y664497D01*
X433180Y664750D01*
X432517Y664624D01*
X431949Y664245D01*
X431570Y663361D01*
X431381Y662604D01*
Y661846D01*
X431570Y661089D01*
X432044Y660331D01*
X432612Y659826D01*
X433275Y659700D01*
X433937Y659952D01*
X434600Y660710D01*
G01X440565Y659448D02*
X440376Y659574D01*
Y659826D01*
X440565Y659952D01*
X440755Y659826D01*
Y659574D01*
X440565Y659448D01*
G01Y662856D02*
X440376Y662982D01*
Y663235D01*
X440565Y663361D01*
X440755Y663235D01*
Y662982D01*
X440565Y662856D01*
G01X453727Y659700D02*
Y667275D01*
G01X457704D02*
Y659700D01*
G01Y663487D02*
X453727D01*
G01X463290Y659700D02*
X462722Y659826D01*
X462154Y660331D01*
X461775Y661215D01*
X461586Y662225D01*
X461775Y663235D01*
X462154Y664119D01*
X462722Y664624D01*
X463290Y664750D01*
X463859Y664624D01*
X464427Y664119D01*
X464805Y663235D01*
X464900Y662225D01*
X464805Y661215D01*
X464427Y660331D01*
X463859Y659826D01*
X463290Y659700D01*
G01X470865D02*
Y667275D01*
G01X477020Y663109D02*
X480050D01*
X479766Y663993D01*
X479293Y664497D01*
X478630Y664750D01*
X477967Y664624D01*
X477399Y664245D01*
X477020Y663361D01*
X476831Y662604D01*
Y661846D01*
X477020Y661089D01*
X477494Y660331D01*
X478062Y659826D01*
X478725Y659700D01*
X479387Y659952D01*
X480050Y660710D01*
G01X491507Y659700D02*
Y667275D01*
X493401D01*
X494159Y666896D01*
X494727Y666391D01*
X495200Y665634D01*
X495579Y664750D01*
X495674Y663487D01*
X495579Y662225D01*
X495200Y661341D01*
X494727Y660584D01*
X494159Y660079D01*
X493401Y659700D01*
X491507D01*
G01X501165Y664750D02*
Y659700D01*
G01Y666770D02*
X500976Y666896D01*
Y667149D01*
X501165Y667275D01*
X501355Y667149D01*
Y666896D01*
X501165Y666770D01*
G01X510445Y659700D02*
Y664750D01*
G01Y663866D02*
X510066Y664371D01*
X509498Y664624D01*
X508835Y664750D01*
X508172Y664497D01*
X507604Y663993D01*
X507225Y663235D01*
X507036Y662225D01*
X507225Y661215D01*
X507604Y660457D01*
X508172Y659952D01*
X508835Y659700D01*
X509498Y659826D01*
X510066Y660205D01*
X510445Y660710D01*
G01X516315Y659448D02*
X516126Y659574D01*
Y659826D01*
X516315Y659952D01*
X516505Y659826D01*
Y659574D01*
X516315Y659448D01*
G01X521807Y661215D02*
X522375Y660331D01*
X523133Y659826D01*
X523985Y659700D01*
X524743Y659826D01*
X525500Y660457D01*
X525974Y661215D01*
X526068Y661972D01*
X525879Y662856D01*
X525216Y663487D01*
X524553Y663740D01*
X523701D01*
G01X524553D02*
X525121Y664119D01*
X525595Y664750D01*
X525784Y665507D01*
X525595Y666265D01*
X525121Y666896D01*
X524269Y667275D01*
X523417Y667149D01*
X522565Y666644D01*
G01X531465Y659448D02*
X531276Y659574D01*
Y659826D01*
X531465Y659952D01*
X531655Y659826D01*
Y659574D01*
X531465Y659448D01*
G01X539040Y659700D02*
Y667275D01*
X537904Y665760D01*
G01Y659700D02*
X540177D01*
G01X546615D02*
X547278Y659826D01*
X548036Y660205D01*
X548509Y660836D01*
X548699Y661720D01*
X548509Y662604D01*
X547941Y663361D01*
X547089Y663740D01*
X546142D01*
X545574Y663993D01*
X545100Y664624D01*
X544911Y665507D01*
X545195Y666391D01*
X545858Y667023D01*
X546615Y667275D01*
X547373Y667023D01*
X548036Y666391D01*
X548320Y665507D01*
X548130Y664624D01*
X547657Y663993D01*
X547089Y663740D01*
X546142D01*
X545290Y663361D01*
X544722Y662604D01*
X544532Y661720D01*
X544722Y660836D01*
X545195Y660205D01*
X545953Y659826D01*
X546615Y659700D01*
G01X551350D02*
Y664750D01*
G01Y663361D02*
X551634Y663993D01*
X552107Y664497D01*
X552770Y664750D01*
X553433Y664497D01*
X553906Y663993D01*
X554190Y663361D01*
Y659700D01*
G01Y663361D02*
X554475Y663993D01*
X554948Y664497D01*
X555611Y664750D01*
X556274Y664497D01*
X556747Y663993D01*
X557031Y663235D01*
Y659700D01*
G01X558925D02*
Y664750D01*
G01Y663361D02*
X559209Y663993D01*
X559682Y664497D01*
X560345Y664750D01*
X561008Y664497D01*
X561481Y663993D01*
X561765Y663361D01*
Y659700D01*
G01Y663361D02*
X562050Y663993D01*
X562523Y664497D01*
X563186Y664750D01*
X563849Y664497D01*
X564322Y663993D01*
X564606Y663235D01*
Y659700D01*
G01X576915Y664750D02*
Y659700D01*
G01Y666770D02*
X576726Y666896D01*
Y667149D01*
X576915Y667275D01*
X577105Y667149D01*
Y666896D01*
X576915Y666770D01*
G01X583070Y660584D02*
X583544Y660079D01*
X584206Y659700D01*
X584775D01*
X585343Y659952D01*
X585721Y660331D01*
X585911Y660836D01*
X585816Y661594D01*
X585437Y661972D01*
X583733Y662730D01*
X583354Y663614D01*
X583544Y664245D01*
X583922Y664624D01*
X584490Y664750D01*
X585059Y664624D01*
X585627Y664245D01*
G01X596800Y659700D02*
Y664750D01*
G01Y663361D02*
X597084Y663993D01*
X597557Y664497D01*
X598220Y664750D01*
X598883Y664497D01*
X599356Y663993D01*
X599640Y663361D01*
Y659700D01*
G01Y663361D02*
X599925Y663993D01*
X600398Y664497D01*
X601061Y664750D01*
X601724Y664497D01*
X602197Y663993D01*
X602481Y663235D01*
Y659700D01*
G01X608920D02*
Y664750D01*
G01Y663866D02*
X608541Y664371D01*
X607973Y664624D01*
X607310Y664750D01*
X606647Y664497D01*
X606079Y663993D01*
X605700Y663235D01*
X605511Y662225D01*
X605700Y661215D01*
X606079Y660457D01*
X606647Y659952D01*
X607310Y659700D01*
X607973Y659826D01*
X608541Y660205D01*
X608920Y660710D01*
G01X613465Y659700D02*
Y664750D01*
G01Y663740D02*
X613938Y664245D01*
X614412Y664624D01*
X615075Y664750D01*
X615548Y664624D01*
X616116Y664245D01*
G01X620756Y659700D02*
Y667275D01*
G01X623786Y664750D02*
X620756Y661846D01*
G01X621987Y662982D02*
X623975Y659700D01*
G01X628520Y663109D02*
X631550D01*
X631266Y663993D01*
X630793Y664497D01*
X630130Y664750D01*
X629467Y664624D01*
X628899Y664245D01*
X628520Y663361D01*
X628331Y662604D01*
Y661846D01*
X628520Y661089D01*
X628994Y660331D01*
X629562Y659826D01*
X630225Y659700D01*
X630887Y659952D01*
X631550Y660710D01*
G01X639220Y667275D02*
Y659700D01*
G01Y660836D02*
X638841Y660205D01*
X638273Y659826D01*
X637610Y659700D01*
X636853Y659952D01*
X636285Y660584D01*
X635906Y661341D01*
X635811Y662225D01*
X635906Y663109D01*
X636285Y663866D01*
X636853Y664497D01*
X637610Y664750D01*
X638273Y664624D01*
X638746Y664371D01*
X639220Y663866D01*
G01X652665Y664750D02*
Y659700D01*
G01Y666770D02*
X652476Y666896D01*
Y667149D01*
X652665Y667275D01*
X652855Y667149D01*
Y666896D01*
X652665Y666770D01*
G01X658631Y659700D02*
Y664750D01*
G01Y663487D02*
X659010Y664119D01*
X659578Y664624D01*
X660335Y664750D01*
X660998Y664624D01*
X661566Y664119D01*
X661850Y663235D01*
Y659700D01*
G01X672550D02*
Y664750D01*
G01Y663361D02*
X672834Y663993D01*
X673307Y664497D01*
X673970Y664750D01*
X674633Y664497D01*
X675106Y663993D01*
X675390Y663361D01*
Y659700D01*
G01Y663361D02*
X675675Y663993D01*
X676148Y664497D01*
X676811Y664750D01*
X677474Y664497D01*
X677947Y663993D01*
X678231Y663235D01*
Y659700D01*
G01X681545Y663109D02*
X684575D01*
X684291Y663993D01*
X683818Y664497D01*
X683155Y664750D01*
X682492Y664624D01*
X681924Y664245D01*
X681545Y663361D01*
X681356Y662604D01*
Y661846D01*
X681545Y661089D01*
X682019Y660331D01*
X682587Y659826D01*
X683250Y659700D01*
X683912Y659952D01*
X684575Y660710D01*
G01X692055Y664119D02*
X691393Y664624D01*
X690825Y664750D01*
X690067Y664497D01*
X689499Y663993D01*
X689120Y663109D01*
X689025Y662225D01*
X689120Y661341D01*
X689499Y660584D01*
X690067Y659952D01*
X690825Y659700D01*
X691487Y659952D01*
X692055Y660457D01*
G01X696506Y659700D02*
Y667275D01*
G01Y663614D02*
X696979Y664245D01*
X697453Y664624D01*
X698210Y664750D01*
X698778Y664624D01*
X699441Y664119D01*
X699725Y663361D01*
Y659700D01*
G01X707395D02*
Y664750D01*
G01Y663866D02*
X707016Y664371D01*
X706448Y664624D01*
X705785Y664750D01*
X705122Y664497D01*
X704554Y663993D01*
X704175Y663235D01*
X703986Y662225D01*
X704175Y661215D01*
X704554Y660457D01*
X705122Y659952D01*
X705785Y659700D01*
X706448Y659826D01*
X707016Y660205D01*
X707395Y660710D01*
G01X711656Y659700D02*
Y664750D01*
G01Y663487D02*
X712035Y664119D01*
X712603Y664624D01*
X713360Y664750D01*
X714023Y664624D01*
X714591Y664119D01*
X714875Y663235D01*
Y659700D01*
G01X720840Y664750D02*
Y659700D01*
G01Y666770D02*
X720651Y666896D01*
Y667149D01*
X720840Y667275D01*
X721030Y667149D01*
Y666896D01*
X720840Y666770D01*
G01X729930Y664119D02*
X729268Y664624D01*
X728700Y664750D01*
X727942Y664497D01*
X727374Y663993D01*
X726995Y663109D01*
X726900Y662225D01*
X726995Y661341D01*
X727374Y660584D01*
X727942Y659952D01*
X728700Y659700D01*
X729362Y659952D01*
X729930Y660457D01*
G01X737695Y659700D02*
Y664750D01*
G01Y663866D02*
X737316Y664371D01*
X736748Y664624D01*
X736085Y664750D01*
X735422Y664497D01*
X734854Y663993D01*
X734475Y663235D01*
X734286Y662225D01*
X734475Y661215D01*
X734854Y660457D01*
X735422Y659952D01*
X736085Y659700D01*
X736748Y659826D01*
X737316Y660205D01*
X737695Y660710D01*
G01X743565Y659700D02*
Y667275D01*
G01X760420D02*
Y659700D01*
G01Y660836D02*
X760041Y660205D01*
X759473Y659826D01*
X758810Y659700D01*
X758053Y659952D01*
X757485Y660584D01*
X757106Y661341D01*
X757011Y662225D01*
X757106Y663109D01*
X757485Y663866D01*
X758053Y664497D01*
X758810Y664750D01*
X759473Y664624D01*
X759946Y664371D01*
X760420Y663866D01*
G01X764965Y659700D02*
Y664750D01*
G01Y663740D02*
X765438Y664245D01*
X765912Y664624D01*
X766575Y664750D01*
X767048Y664624D01*
X767616Y664245D01*
G01X775570Y659700D02*
Y664750D01*
G01Y663866D02*
X775191Y664371D01*
X774623Y664624D01*
X773960Y664750D01*
X773297Y664497D01*
X772729Y663993D01*
X772350Y663235D01*
X772161Y662225D01*
X772350Y661215D01*
X772729Y660457D01*
X773297Y659952D01*
X773960Y659700D01*
X774623Y659826D01*
X775191Y660205D01*
X775570Y660710D01*
G01X779073Y664750D02*
X780210Y659700D01*
X781440Y664750D01*
X782671Y659700D01*
X783808Y664750D01*
G01X789015D02*
Y659700D01*
G01Y666770D02*
X788826Y666896D01*
Y667149D01*
X789015Y667275D01*
X789205Y667149D01*
Y666896D01*
X789015Y666770D01*
G01X794981Y659700D02*
Y664750D01*
G01Y663487D02*
X795360Y664119D01*
X795928Y664624D01*
X796685Y664750D01*
X797348Y664624D01*
X797916Y664119D01*
X798200Y663235D01*
Y659700D01*
G01X802840Y657806D02*
X803503Y657301D01*
X804260Y657175D01*
X804923Y657301D01*
X805491Y657932D01*
X805870Y658816D01*
Y664750D01*
G01Y663740D02*
X805491Y664245D01*
X804923Y664624D01*
X804260Y664750D01*
X803503Y664497D01*
X803029Y663993D01*
X802650Y663109D01*
X802461Y662225D01*
X802556Y661467D01*
X802935Y660584D01*
X803503Y659952D01*
X804260Y659700D01*
X804828Y659826D01*
X805491Y660331D01*
X805870Y660836D01*
G01X821020Y659700D02*
Y664750D01*
G01Y663866D02*
X820641Y664371D01*
X820073Y664624D01*
X819410Y664750D01*
X818747Y664497D01*
X818179Y663993D01*
X817800Y663235D01*
X817611Y662225D01*
X817800Y661215D01*
X818179Y660457D01*
X818747Y659952D01*
X819410Y659700D01*
X820073Y659826D01*
X820641Y660205D01*
X821020Y660710D01*
G01X825281Y659700D02*
Y664750D01*
G01Y663487D02*
X825660Y664119D01*
X826228Y664624D01*
X826985Y664750D01*
X827648Y664624D01*
X828216Y664119D01*
X828500Y663235D01*
Y659700D01*
G01X836170Y667275D02*
Y659700D01*
G01Y660836D02*
X835791Y660205D01*
X835223Y659826D01*
X834560Y659700D01*
X833803Y659952D01*
X833235Y660584D01*
X832856Y661341D01*
X832761Y662225D01*
X832856Y663109D01*
X833235Y663866D01*
X833803Y664497D01*
X834560Y664750D01*
X835223Y664624D01*
X835696Y664371D01*
X836170Y663866D01*
G01X848006Y659700D02*
Y667275D01*
G01Y663614D02*
X848479Y664245D01*
X848953Y664624D01*
X849710Y664750D01*
X850278Y664624D01*
X850941Y664119D01*
X851225Y663361D01*
Y659700D01*
G01X857190D02*
X856622Y659826D01*
X856054Y660331D01*
X855675Y661215D01*
X855486Y662225D01*
X855675Y663235D01*
X856054Y664119D01*
X856622Y664624D01*
X857190Y664750D01*
X857759Y664624D01*
X858327Y664119D01*
X858705Y663235D01*
X858800Y662225D01*
X858705Y661215D01*
X858327Y660331D01*
X857759Y659826D01*
X857190Y659700D01*
G01X864765D02*
Y667275D01*
G01X870920Y663109D02*
X873950D01*
X873666Y663993D01*
X873193Y664497D01*
X872530Y664750D01*
X871867Y664624D01*
X871299Y664245D01*
X870920Y663361D01*
X870731Y662604D01*
Y661846D01*
X870920Y661089D01*
X871394Y660331D01*
X871962Y659826D01*
X872625Y659700D01*
X873287Y659952D01*
X873950Y660710D01*
G01X885407Y659700D02*
Y667275D01*
X887301D01*
X888059Y666896D01*
X888627Y666391D01*
X889100Y665634D01*
X889479Y664750D01*
X889574Y663487D01*
X889479Y662225D01*
X889100Y661341D01*
X888627Y660584D01*
X888059Y660079D01*
X887301Y659700D01*
X885407D01*
G01X895065Y664750D02*
Y659700D01*
G01Y666770D02*
X894876Y666896D01*
Y667149D01*
X895065Y667275D01*
X895255Y667149D01*
Y666896D01*
X895065Y666770D01*
G01X904345Y659700D02*
Y664750D01*
G01Y663866D02*
X903966Y664371D01*
X903398Y664624D01*
X902735Y664750D01*
X902072Y664497D01*
X901504Y663993D01*
X901125Y663235D01*
X900936Y662225D01*
X901125Y661215D01*
X901504Y660457D01*
X902072Y659952D01*
X902735Y659700D01*
X903398Y659826D01*
X903966Y660205D01*
X904345Y660710D01*
G01X910215Y659448D02*
X910026Y659574D01*
Y659826D01*
X910215Y659952D01*
X910405Y659826D01*
Y659574D01*
X910215Y659448D01*
G01X925365Y659700D02*
Y667275D01*
X924229Y665760D01*
G01Y659700D02*
X926502D01*
G01X931141Y666013D02*
X931710Y666770D01*
X932372Y667149D01*
X933130Y667275D01*
X934077Y667023D01*
X934740Y666391D01*
X934929Y665634D01*
X934834Y664876D01*
X934455Y664245D01*
X932562Y662982D01*
X931710Y662099D01*
X931141Y660836D01*
X930952Y659700D01*
X934929D01*
G01X938716Y662856D02*
X939379Y663740D01*
X939947Y664245D01*
X940705Y664497D01*
X941368Y664245D01*
X941841Y663740D01*
X942220Y662982D01*
X942315Y662099D01*
X942220Y661341D01*
X941841Y660584D01*
X941273Y659952D01*
X940610Y659700D01*
X939853Y659952D01*
X939190Y660710D01*
X938811Y661846D01*
X938716Y663109D01*
X938906Y664750D01*
X939190Y665634D01*
X939663Y666517D01*
X940326Y667149D01*
X940989Y667275D01*
X941652Y667023D01*
X942125Y666391D01*
G01X945250Y659700D02*
Y664750D01*
G01Y663361D02*
X945534Y663993D01*
X946007Y664497D01*
X946670Y664750D01*
X947333Y664497D01*
X947806Y663993D01*
X948090Y663361D01*
Y659700D01*
G01Y663361D02*
X948375Y663993D01*
X948848Y664497D01*
X949511Y664750D01*
X950174Y664497D01*
X950647Y663993D01*
X950931Y663235D01*
Y659700D01*
G01X955665Y664750D02*
Y659700D01*
G01Y666770D02*
X955476Y666896D01*
Y667149D01*
X955665Y667275D01*
X955855Y667149D01*
Y666896D01*
X955665Y666770D01*
G01X963240Y659700D02*
Y667275D01*
G01X978390Y664750D02*
Y659700D01*
G01Y666770D02*
X978201Y666896D01*
Y667149D01*
X978390Y667275D01*
X978580Y667149D01*
Y666896D01*
X978390Y666770D01*
G01X984545Y660584D02*
X985019Y660079D01*
X985681Y659700D01*
X986250D01*
X986818Y659952D01*
X987196Y660331D01*
X987386Y660836D01*
X987291Y661594D01*
X986912Y661972D01*
X985208Y662730D01*
X984829Y663614D01*
X985019Y664245D01*
X985397Y664624D01*
X985965Y664750D01*
X986534Y664624D01*
X987102Y664245D01*
G01X998275Y659700D02*
Y664750D01*
G01Y663361D02*
X998559Y663993D01*
X999032Y664497D01*
X999695Y664750D01*
X1000358Y664497D01*
X1000831Y663993D01*
X1001115Y663361D01*
Y659700D01*
G01Y663361D02*
X1001400Y663993D01*
X1001873Y664497D01*
X1002536Y664750D01*
X1003199Y664497D01*
X1003672Y663993D01*
X1003956Y663235D01*
Y659700D01*
G01X1010395D02*
Y664750D01*
G01Y663866D02*
X1010016Y664371D01*
X1009448Y664624D01*
X1008785Y664750D01*
X1008122Y664497D01*
X1007554Y663993D01*
X1007175Y663235D01*
X1006986Y662225D01*
X1007175Y661215D01*
X1007554Y660457D01*
X1008122Y659952D01*
X1008785Y659700D01*
X1009448Y659826D01*
X1010016Y660205D01*
X1010395Y660710D01*
G01X1014940Y659700D02*
Y664750D01*
G01Y663740D02*
X1015413Y664245D01*
X1015887Y664624D01*
X1016550Y664750D01*
X1017023Y664624D01*
X1017591Y664245D01*
G01X1022231Y659700D02*
Y667275D01*
G01X1025261Y664750D02*
X1022231Y661846D01*
G01X1023462Y662982D02*
X1025450Y659700D01*
G01X1029995Y663109D02*
X1033025D01*
X1032741Y663993D01*
X1032268Y664497D01*
X1031605Y664750D01*
X1030942Y664624D01*
X1030374Y664245D01*
X1029995Y663361D01*
X1029806Y662604D01*
Y661846D01*
X1029995Y661089D01*
X1030469Y660331D01*
X1031037Y659826D01*
X1031700Y659700D01*
X1032362Y659952D01*
X1033025Y660710D01*
G01X1040695Y667275D02*
Y659700D01*
G01Y660836D02*
X1040316Y660205D01*
X1039748Y659826D01*
X1039085Y659700D01*
X1038328Y659952D01*
X1037760Y660584D01*
X1037381Y661341D01*
X1037286Y662225D01*
X1037381Y663109D01*
X1037760Y663866D01*
X1038328Y664497D01*
X1039085Y664750D01*
X1039748Y664624D01*
X1040221Y664371D01*
X1040695Y663866D01*
G01X1054140Y664750D02*
Y659700D01*
G01Y666770D02*
X1053951Y666896D01*
Y667149D01*
X1054140Y667275D01*
X1054330Y667149D01*
Y666896D01*
X1054140Y666770D01*
G01X1060106Y659700D02*
Y664750D01*
G01Y663487D02*
X1060485Y664119D01*
X1061053Y664624D01*
X1061810Y664750D01*
X1062473Y664624D01*
X1063041Y664119D01*
X1063325Y663235D01*
Y659700D01*
G01X1077434Y663487D02*
X1079327D01*
Y661215D01*
X1078759Y660457D01*
X1078096Y659952D01*
X1077150Y659700D01*
X1076203Y659952D01*
X1075540Y660457D01*
X1074972Y661215D01*
X1074593Y662099D01*
X1074404Y663109D01*
Y663993D01*
X1074593Y664750D01*
X1074972Y665634D01*
X1075540Y666391D01*
X1076108Y666896D01*
X1076865Y667275D01*
X1077528D01*
X1078286Y667023D01*
X1078854Y666517D01*
G01X1083020Y663109D02*
X1086050D01*
X1085766Y663993D01*
X1085293Y664497D01*
X1084630Y664750D01*
X1083967Y664624D01*
X1083399Y664245D01*
X1083020Y663361D01*
X1082831Y662604D01*
Y661846D01*
X1083020Y661089D01*
X1083494Y660331D01*
X1084062Y659826D01*
X1084725Y659700D01*
X1085387Y659952D01*
X1086050Y660710D01*
G01X1090690Y659700D02*
Y664750D01*
G01Y663740D02*
X1091163Y664245D01*
X1091637Y664624D01*
X1092300Y664750D01*
X1092773Y664624D01*
X1093341Y664245D01*
G01X1097886Y659700D02*
Y667275D01*
G01Y663487D02*
X1098360Y664245D01*
X1098928Y664624D01*
X1099496Y664750D01*
X1100348Y664497D01*
X1100916Y663993D01*
X1101295Y663109D01*
Y662099D01*
X1101105Y661089D01*
X1100727Y660331D01*
X1100064Y659826D01*
X1099496Y659700D01*
X1098928Y659826D01*
X1098360Y660205D01*
X1097886Y660836D01*
G01X1105745Y663109D02*
X1108775D01*
X1108491Y663993D01*
X1108018Y664497D01*
X1107355Y664750D01*
X1106692Y664624D01*
X1106124Y664245D01*
X1105745Y663361D01*
X1105556Y662604D01*
Y661846D01*
X1105745Y661089D01*
X1106219Y660331D01*
X1106787Y659826D01*
X1107450Y659700D01*
X1108112Y659952D01*
X1108775Y660710D01*
G01X1113415Y659700D02*
Y664750D01*
G01Y663740D02*
X1113888Y664245D01*
X1114362Y664624D01*
X1115025Y664750D01*
X1115498Y664624D01*
X1116066Y664245D01*
G01X1129322Y659700D02*
Y666139D01*
X1129512Y666770D01*
X1129890Y667149D01*
X1130459Y667275D01*
X1131027Y667023D01*
X1131311Y666391D01*
G01X1130175Y664245D02*
X1128281D01*
G01X1137465Y664750D02*
Y659700D01*
G01Y666770D02*
X1137276Y666896D01*
Y667149D01*
X1137465Y667275D01*
X1137655Y667149D01*
Y666896D01*
X1137465Y666770D01*
G01X1145040Y659700D02*
Y667275D01*
G01X1151195Y663109D02*
X1154225D01*
X1153941Y663993D01*
X1153468Y664497D01*
X1152805Y664750D01*
X1152142Y664624D01*
X1151574Y664245D01*
X1151195Y663361D01*
X1151006Y662604D01*
Y661846D01*
X1151195Y661089D01*
X1151669Y660331D01*
X1152237Y659826D01*
X1152900Y659700D01*
X1153562Y659952D01*
X1154225Y660710D01*
G01X1160190Y659448D02*
X1160001Y659574D01*
Y659826D01*
X1160190Y659952D01*
X1160380Y659826D01*
Y659574D01*
X1160190Y659448D01*
G01X355457Y691375D02*
Y685946D01*
X355836Y684810D01*
X356594Y684052D01*
X357540Y683800D01*
X358487Y684052D01*
X359245Y684810D01*
X359624Y685946D01*
Y691375D01*
G01X363506Y683800D02*
Y688850D01*
G01Y687587D02*
X363885Y688219D01*
X364453Y688724D01*
X365210Y688850D01*
X365873Y688724D01*
X366441Y688219D01*
X366725Y687335D01*
Y683800D01*
G01X372690Y688850D02*
Y683800D01*
G01Y690870D02*
X372501Y690996D01*
Y691249D01*
X372690Y691375D01*
X372880Y691249D01*
Y690996D01*
X372690Y690870D01*
G01X380265Y691375D02*
Y683800D01*
G01X378940Y688850D02*
X381591D01*
G01X396930Y688219D02*
X396268Y688724D01*
X395700Y688850D01*
X394942Y688597D01*
X394374Y688093D01*
X393995Y687209D01*
X393900Y686325D01*
X393995Y685441D01*
X394374Y684684D01*
X394942Y684052D01*
X395700Y683800D01*
X396362Y684052D01*
X396930Y684557D01*
G01X402990Y683800D02*
X402422Y683926D01*
X401854Y684431D01*
X401475Y685315D01*
X401286Y686325D01*
X401475Y687335D01*
X401854Y688219D01*
X402422Y688724D01*
X402990Y688850D01*
X403559Y688724D01*
X404127Y688219D01*
X404505Y687335D01*
X404600Y686325D01*
X404505Y685315D01*
X404127Y684431D01*
X403559Y683926D01*
X402990Y683800D01*
G01X408956D02*
Y688850D01*
G01Y687587D02*
X409335Y688219D01*
X409903Y688724D01*
X410660Y688850D01*
X411323Y688724D01*
X411891Y688219D01*
X412175Y687335D01*
Y683800D01*
G01X416436Y688850D02*
X418140Y683800D01*
X419845Y688850D01*
G01X424295Y687209D02*
X427325D01*
X427041Y688093D01*
X426568Y688597D01*
X425905Y688850D01*
X425242Y688724D01*
X424674Y688345D01*
X424295Y687461D01*
X424106Y686704D01*
Y685946D01*
X424295Y685189D01*
X424769Y684431D01*
X425337Y683926D01*
X426000Y683800D01*
X426662Y684052D01*
X427325Y684810D01*
G01X431965Y683800D02*
Y688850D01*
G01Y687840D02*
X432438Y688345D01*
X432912Y688724D01*
X433575Y688850D01*
X434048Y688724D01*
X434616Y688345D01*
G01X439445Y684684D02*
X439919Y684179D01*
X440581Y683800D01*
X441150D01*
X441718Y684052D01*
X442096Y684431D01*
X442286Y684936D01*
X442191Y685694D01*
X441812Y686072D01*
X440108Y686830D01*
X439729Y687714D01*
X439919Y688345D01*
X440297Y688724D01*
X440865Y688850D01*
X441434Y688724D01*
X442002Y688345D01*
G01X448440Y688850D02*
Y683800D01*
G01Y690870D02*
X448251Y690996D01*
Y691249D01*
X448440Y691375D01*
X448630Y691249D01*
Y690996D01*
X448440Y690870D01*
G01X456015Y683800D02*
X455447Y683926D01*
X454879Y684431D01*
X454500Y685315D01*
X454311Y686325D01*
X454500Y687335D01*
X454879Y688219D01*
X455447Y688724D01*
X456015Y688850D01*
X456584Y688724D01*
X457152Y688219D01*
X457530Y687335D01*
X457625Y686325D01*
X457530Y685315D01*
X457152Y684431D01*
X456584Y683926D01*
X456015Y683800D01*
G01X461981D02*
Y688850D01*
G01Y687587D02*
X462360Y688219D01*
X462928Y688724D01*
X463685Y688850D01*
X464348Y688724D01*
X464916Y688219D01*
X465200Y687335D01*
Y683800D01*
G01X477320Y687209D02*
X480350D01*
X480066Y688093D01*
X479593Y688597D01*
X478930Y688850D01*
X478267Y688724D01*
X477699Y688345D01*
X477320Y687461D01*
X477131Y686704D01*
Y685946D01*
X477320Y685189D01*
X477794Y684431D01*
X478362Y683926D01*
X479025Y683800D01*
X479687Y684052D01*
X480350Y684810D01*
G01X484990Y683800D02*
Y688850D01*
G01Y687840D02*
X485463Y688345D01*
X485937Y688724D01*
X486600Y688850D01*
X487073Y688724D01*
X487641Y688345D01*
G01X492565Y683800D02*
Y688850D01*
G01Y687840D02*
X493038Y688345D01*
X493512Y688724D01*
X494175Y688850D01*
X494648Y688724D01*
X495216Y688345D01*
G01X501465Y683800D02*
X500897Y683926D01*
X500329Y684431D01*
X499950Y685315D01*
X499761Y686325D01*
X499950Y687335D01*
X500329Y688219D01*
X500897Y688724D01*
X501465Y688850D01*
X502034Y688724D01*
X502602Y688219D01*
X502980Y687335D01*
X503075Y686325D01*
X502980Y685315D01*
X502602Y684431D01*
X502034Y683926D01*
X501465Y683800D01*
G01X507715D02*
Y688850D01*
G01Y687840D02*
X508188Y688345D01*
X508662Y688724D01*
X509325Y688850D01*
X509798Y688724D01*
X510366Y688345D01*
G01X522486Y683800D02*
Y691375D01*
G01Y687587D02*
X522960Y688345D01*
X523528Y688724D01*
X524096Y688850D01*
X524948Y688597D01*
X525516Y688093D01*
X525895Y687209D01*
Y686199D01*
X525705Y685189D01*
X525327Y684431D01*
X524664Y683926D01*
X524096Y683800D01*
X523528Y683926D01*
X522960Y684305D01*
X522486Y684936D01*
G01X530345Y687209D02*
X533375D01*
X533091Y688093D01*
X532618Y688597D01*
X531955Y688850D01*
X531292Y688724D01*
X530724Y688345D01*
X530345Y687461D01*
X530156Y686704D01*
Y685946D01*
X530345Y685189D01*
X530819Y684431D01*
X531387Y683926D01*
X532050Y683800D01*
X532712Y684052D01*
X533375Y684810D01*
G01X539340Y691375D02*
Y683800D01*
G01X538015Y688850D02*
X540666D01*
G01X544548D02*
X545685Y683800D01*
X546915Y688850D01*
X548146Y683800D01*
X549283Y688850D01*
G01X553070Y687209D02*
X556100D01*
X555816Y688093D01*
X555343Y688597D01*
X554680Y688850D01*
X554017Y688724D01*
X553449Y688345D01*
X553070Y687461D01*
X552881Y686704D01*
Y685946D01*
X553070Y685189D01*
X553544Y684431D01*
X554112Y683926D01*
X554775Y683800D01*
X555437Y684052D01*
X556100Y684810D01*
G01X560645Y687209D02*
X563675D01*
X563391Y688093D01*
X562918Y688597D01*
X562255Y688850D01*
X561592Y688724D01*
X561024Y688345D01*
X560645Y687461D01*
X560456Y686704D01*
Y685946D01*
X560645Y685189D01*
X561119Y684431D01*
X561687Y683926D01*
X562350Y683800D01*
X563012Y684052D01*
X563675Y684810D01*
G01X568031Y683800D02*
Y688850D01*
G01Y687587D02*
X568410Y688219D01*
X568978Y688724D01*
X569735Y688850D01*
X570398Y688724D01*
X570966Y688219D01*
X571250Y687335D01*
Y683800D01*
G01X581950D02*
Y688850D01*
G01Y687461D02*
X582234Y688093D01*
X582707Y688597D01*
X583370Y688850D01*
X584033Y688597D01*
X584506Y688093D01*
X584790Y687461D01*
Y683800D01*
G01Y687461D02*
X585075Y688093D01*
X585548Y688597D01*
X586211Y688850D01*
X586874Y688597D01*
X587347Y688093D01*
X587631Y687335D01*
Y683800D01*
G01X590945Y687209D02*
X593975D01*
X593691Y688093D01*
X593218Y688597D01*
X592555Y688850D01*
X591892Y688724D01*
X591324Y688345D01*
X590945Y687461D01*
X590756Y686704D01*
Y685946D01*
X590945Y685189D01*
X591419Y684431D01*
X591987Y683926D01*
X592650Y683800D01*
X593312Y684052D01*
X593975Y684810D01*
G01X599940Y691375D02*
Y683800D01*
G01X598615Y688850D02*
X601266D01*
G01X606190Y683800D02*
Y688850D01*
G01Y687840D02*
X606663Y688345D01*
X607137Y688724D01*
X607800Y688850D01*
X608273Y688724D01*
X608841Y688345D01*
G01X615090Y688850D02*
Y683800D01*
G01Y690870D02*
X614901Y690996D01*
Y691249D01*
X615090Y691375D01*
X615280Y691249D01*
Y690996D01*
X615090Y690870D01*
G01X624180Y688219D02*
X623518Y688724D01*
X622950Y688850D01*
X622192Y688597D01*
X621624Y688093D01*
X621245Y687209D01*
X621150Y686325D01*
X621245Y685441D01*
X621624Y684684D01*
X622192Y684052D01*
X622950Y683800D01*
X623612Y684052D01*
X624180Y684557D01*
G01X639520Y683800D02*
Y688850D01*
G01Y687966D02*
X639141Y688471D01*
X638573Y688724D01*
X637910Y688850D01*
X637247Y688597D01*
X636679Y688093D01*
X636300Y687335D01*
X636111Y686325D01*
X636300Y685315D01*
X636679Y684557D01*
X637247Y684052D01*
X637910Y683800D01*
X638573Y683926D01*
X639141Y684305D01*
X639520Y684810D01*
G01X643781Y683800D02*
Y688850D01*
G01Y687587D02*
X644160Y688219D01*
X644728Y688724D01*
X645485Y688850D01*
X646148Y688724D01*
X646716Y688219D01*
X647000Y687335D01*
Y683800D01*
G01X654670Y691375D02*
Y683800D01*
G01Y684936D02*
X654291Y684305D01*
X653723Y683926D01*
X653060Y683800D01*
X652303Y684052D01*
X651735Y684684D01*
X651356Y685441D01*
X651261Y686325D01*
X651356Y687209D01*
X651735Y687966D01*
X652303Y688597D01*
X653060Y688850D01*
X653723Y688724D01*
X654196Y688471D01*
X654670Y687966D01*
G01X670009Y683800D02*
X666222D01*
Y691375D01*
X670009D01*
G01X668494Y687714D02*
X666222D01*
G01X674081Y683800D02*
Y688850D01*
G01Y687587D02*
X674460Y688219D01*
X675028Y688724D01*
X675785Y688850D01*
X676448Y688724D01*
X677016Y688219D01*
X677300Y687335D01*
Y683800D01*
G01X681940Y681906D02*
X682603Y681401D01*
X683360Y681275D01*
X684023Y681401D01*
X684591Y682032D01*
X684970Y682916D01*
Y688850D01*
G01Y687840D02*
X684591Y688345D01*
X684023Y688724D01*
X683360Y688850D01*
X682603Y688597D01*
X682129Y688093D01*
X681750Y687209D01*
X681561Y686325D01*
X681656Y685567D01*
X682035Y684684D01*
X682603Y684052D01*
X683360Y683800D01*
X683928Y683926D01*
X684591Y684431D01*
X684970Y684936D01*
G01X690840Y683800D02*
Y691375D01*
G01X698415Y688850D02*
Y683800D01*
G01Y690870D02*
X698226Y690996D01*
Y691249D01*
X698415Y691375D01*
X698605Y691249D01*
Y690996D01*
X698415Y690870D01*
G01X704570Y684684D02*
X705044Y684179D01*
X705706Y683800D01*
X706275D01*
X706843Y684052D01*
X707221Y684431D01*
X707411Y684936D01*
X707316Y685694D01*
X706937Y686072D01*
X705233Y686830D01*
X704854Y687714D01*
X705044Y688345D01*
X705422Y688724D01*
X705990Y688850D01*
X706559Y688724D01*
X707127Y688345D01*
G01X711956Y683800D02*
Y691375D01*
G01Y687714D02*
X712429Y688345D01*
X712903Y688724D01*
X713660Y688850D01*
X714228Y688724D01*
X714891Y688219D01*
X715175Y687461D01*
Y683800D01*
G01X727295Y684684D02*
X727769Y684179D01*
X728431Y683800D01*
X729000D01*
X729568Y684052D01*
X729946Y684431D01*
X730136Y684936D01*
X730041Y685694D01*
X729662Y686072D01*
X727958Y686830D01*
X727579Y687714D01*
X727769Y688345D01*
X728147Y688724D01*
X728715Y688850D01*
X729284Y688724D01*
X729852Y688345D01*
G01X734302Y681528D02*
X734870Y681275D01*
X735628Y681528D01*
X736101Y682032D01*
X736480Y682664D01*
X737048Y684684D01*
X738279Y688850D01*
G01X735249D02*
X737048Y684684D01*
G01X742445D02*
X742919Y684179D01*
X743581Y683800D01*
X744150D01*
X744718Y684052D01*
X745096Y684431D01*
X745286Y684936D01*
X745191Y685694D01*
X744812Y686072D01*
X743108Y686830D01*
X742729Y687714D01*
X742919Y688345D01*
X743297Y688724D01*
X743865Y688850D01*
X744434Y688724D01*
X745002Y688345D01*
G01X751440Y691375D02*
Y683800D01*
G01X750115Y688850D02*
X752766D01*
G01X757595Y687209D02*
X760625D01*
X760341Y688093D01*
X759868Y688597D01*
X759205Y688850D01*
X758542Y688724D01*
X757974Y688345D01*
X757595Y687461D01*
X757406Y686704D01*
Y685946D01*
X757595Y685189D01*
X758069Y684431D01*
X758637Y683926D01*
X759300Y683800D01*
X759962Y684052D01*
X760625Y684810D01*
G01X763750Y683800D02*
Y688850D01*
G01Y687461D02*
X764034Y688093D01*
X764507Y688597D01*
X765170Y688850D01*
X765833Y688597D01*
X766306Y688093D01*
X766590Y687461D01*
Y683800D01*
G01Y687461D02*
X766875Y688093D01*
X767348Y688597D01*
X768011Y688850D01*
X768674Y688597D01*
X769147Y688093D01*
X769431Y687335D01*
Y683800D01*
G01X781740Y688850D02*
Y683800D01*
G01Y690870D02*
X781551Y690996D01*
Y691249D01*
X781740Y691375D01*
X781930Y691249D01*
Y690996D01*
X781740Y690870D01*
G01X787895Y684684D02*
X788369Y684179D01*
X789031Y683800D01*
X789600D01*
X790168Y684052D01*
X790546Y684431D01*
X790736Y684936D01*
X790641Y685694D01*
X790262Y686072D01*
X788558Y686830D01*
X788179Y687714D01*
X788369Y688345D01*
X788747Y688724D01*
X789315Y688850D01*
X789884Y688724D01*
X790452Y688345D01*
G01X804465Y683800D02*
Y691375D01*
G01X810620Y687209D02*
X813650D01*
X813366Y688093D01*
X812893Y688597D01*
X812230Y688850D01*
X811567Y688724D01*
X810999Y688345D01*
X810620Y687461D01*
X810431Y686704D01*
Y685946D01*
X810620Y685189D01*
X811094Y684431D01*
X811662Y683926D01*
X812325Y683800D01*
X812987Y684052D01*
X813650Y684810D01*
G01X818195Y684684D02*
X818669Y684179D01*
X819331Y683800D01*
X819900D01*
X820468Y684052D01*
X820846Y684431D01*
X821036Y684936D01*
X820941Y685694D01*
X820562Y686072D01*
X818858Y686830D01*
X818479Y687714D01*
X818669Y688345D01*
X819047Y688724D01*
X819615Y688850D01*
X820184Y688724D01*
X820752Y688345D01*
G01X825770Y684684D02*
X826244Y684179D01*
X826906Y683800D01*
X827475D01*
X828043Y684052D01*
X828421Y684431D01*
X828611Y684936D01*
X828516Y685694D01*
X828137Y686072D01*
X826433Y686830D01*
X826054Y687714D01*
X826244Y688345D01*
X826622Y688724D01*
X827190Y688850D01*
X827759Y688724D01*
X828327Y688345D01*
G01X842340Y691375D02*
Y683800D01*
G01X841015Y688850D02*
X843666D01*
G01X848306Y683800D02*
Y691375D01*
G01Y687714D02*
X848779Y688345D01*
X849253Y688724D01*
X850010Y688850D01*
X850578Y688724D01*
X851241Y688219D01*
X851525Y687461D01*
Y683800D01*
G01X859195D02*
Y688850D01*
G01Y687966D02*
X858816Y688471D01*
X858248Y688724D01*
X857585Y688850D01*
X856922Y688597D01*
X856354Y688093D01*
X855975Y687335D01*
X855786Y686325D01*
X855975Y685315D01*
X856354Y684557D01*
X856922Y684052D01*
X857585Y683800D01*
X858248Y683926D01*
X858816Y684305D01*
X859195Y684810D01*
G01X863456Y683800D02*
Y688850D01*
G01Y687587D02*
X863835Y688219D01*
X864403Y688724D01*
X865160Y688850D01*
X865823Y688724D01*
X866391Y688219D01*
X866675Y687335D01*
Y683800D01*
G01X880215D02*
Y691375D01*
X879079Y689860D01*
G01Y683800D02*
X881352D01*
G01X892525D02*
Y688850D01*
G01Y687461D02*
X892809Y688093D01*
X893282Y688597D01*
X893945Y688850D01*
X894608Y688597D01*
X895081Y688093D01*
X895365Y687461D01*
Y683800D01*
G01Y687461D02*
X895650Y688093D01*
X896123Y688597D01*
X896786Y688850D01*
X897449Y688597D01*
X897922Y688093D01*
X898206Y687335D01*
Y683800D01*
G01X902940Y688850D02*
Y683800D01*
G01Y690870D02*
X902751Y690996D01*
Y691249D01*
X902940Y691375D01*
X903130Y691249D01*
Y690996D01*
X902940Y690870D01*
G01X910515Y683800D02*
Y691375D01*
G01X917901Y682411D02*
X918280Y684052D01*
G01X931536Y681275D02*
Y688850D01*
G01Y687714D02*
X932010Y688345D01*
X932483Y688724D01*
X933240Y688850D01*
X933903Y688724D01*
X934566Y688093D01*
X934850Y687209D01*
X934945Y686325D01*
X934850Y685441D01*
X934566Y684557D01*
X933998Y684052D01*
X933240Y683800D01*
X932578Y683926D01*
X931915Y684305D01*
X931536Y684810D01*
G01X940815Y683800D02*
Y691375D01*
G01X946970Y687209D02*
X950000D01*
X949716Y688093D01*
X949243Y688597D01*
X948580Y688850D01*
X947917Y688724D01*
X947349Y688345D01*
X946970Y687461D01*
X946781Y686704D01*
Y685946D01*
X946970Y685189D01*
X947444Y684431D01*
X948012Y683926D01*
X948675Y683800D01*
X949337Y684052D01*
X950000Y684810D01*
G01X957670Y683800D02*
Y688850D01*
G01Y687966D02*
X957291Y688471D01*
X956723Y688724D01*
X956060Y688850D01*
X955397Y688597D01*
X954829Y688093D01*
X954450Y687335D01*
X954261Y686325D01*
X954450Y685315D01*
X954829Y684557D01*
X955397Y684052D01*
X956060Y683800D01*
X956723Y683926D01*
X957291Y684305D01*
X957670Y684810D01*
G01X962120Y684684D02*
X962594Y684179D01*
X963256Y683800D01*
X963825D01*
X964393Y684052D01*
X964771Y684431D01*
X964961Y684936D01*
X964866Y685694D01*
X964487Y686072D01*
X962783Y686830D01*
X962404Y687714D01*
X962594Y688345D01*
X962972Y688724D01*
X963540Y688850D01*
X964109Y688724D01*
X964677Y688345D01*
G01X969695Y687209D02*
X972725D01*
X972441Y688093D01*
X971968Y688597D01*
X971305Y688850D01*
X970642Y688724D01*
X970074Y688345D01*
X969695Y687461D01*
X969506Y686704D01*
Y685946D01*
X969695Y685189D01*
X970169Y684431D01*
X970737Y683926D01*
X971400Y683800D01*
X972062Y684052D01*
X972725Y684810D01*
G01X985697Y683800D02*
Y690239D01*
X985887Y690870D01*
X986265Y691249D01*
X986834Y691375D01*
X987402Y691123D01*
X987686Y690491D01*
G01X986550Y688345D02*
X984656D01*
G01X993840Y683800D02*
X993272Y683926D01*
X992704Y684431D01*
X992325Y685315D01*
X992136Y686325D01*
X992325Y687335D01*
X992704Y688219D01*
X993272Y688724D01*
X993840Y688850D01*
X994409Y688724D01*
X994977Y688219D01*
X995355Y687335D01*
X995450Y686325D01*
X995355Y685315D01*
X994977Y684431D01*
X994409Y683926D01*
X993840Y683800D01*
G01X1001415D02*
Y691375D01*
G01X1008990Y683800D02*
Y691375D01*
G01X1016565Y683800D02*
X1015997Y683926D01*
X1015429Y684431D01*
X1015050Y685315D01*
X1014861Y686325D01*
X1015050Y687335D01*
X1015429Y688219D01*
X1015997Y688724D01*
X1016565Y688850D01*
X1017134Y688724D01*
X1017702Y688219D01*
X1018080Y687335D01*
X1018175Y686325D01*
X1018080Y685315D01*
X1017702Y684431D01*
X1017134Y683926D01*
X1016565Y683800D01*
G01X1021773Y688850D02*
X1022910Y683800D01*
X1024140Y688850D01*
X1025371Y683800D01*
X1026508Y688850D01*
G01X1036450Y683800D02*
Y688850D01*
G01Y687461D02*
X1036734Y688093D01*
X1037207Y688597D01*
X1037870Y688850D01*
X1038533Y688597D01*
X1039006Y688093D01*
X1039290Y687461D01*
Y683800D01*
G01Y687461D02*
X1039575Y688093D01*
X1040048Y688597D01*
X1040711Y688850D01*
X1041374Y688597D01*
X1041847Y688093D01*
X1042131Y687335D01*
Y683800D01*
G01X1045445Y687209D02*
X1048475D01*
X1048191Y688093D01*
X1047718Y688597D01*
X1047055Y688850D01*
X1046392Y688724D01*
X1045824Y688345D01*
X1045445Y687461D01*
X1045256Y686704D01*
Y685946D01*
X1045445Y685189D01*
X1045919Y684431D01*
X1046487Y683926D01*
X1047150Y683800D01*
X1047812Y684052D01*
X1048475Y684810D01*
G01X1055955Y688219D02*
X1055293Y688724D01*
X1054725Y688850D01*
X1053967Y688597D01*
X1053399Y688093D01*
X1053020Y687209D01*
X1052925Y686325D01*
X1053020Y685441D01*
X1053399Y684684D01*
X1053967Y684052D01*
X1054725Y683800D01*
X1055387Y684052D01*
X1055955Y684557D01*
G01X1060406Y683800D02*
Y691375D01*
G01Y687714D02*
X1060879Y688345D01*
X1061353Y688724D01*
X1062110Y688850D01*
X1062678Y688724D01*
X1063341Y688219D01*
X1063625Y687461D01*
Y683800D01*
G01X1071295D02*
Y688850D01*
G01Y687966D02*
X1070916Y688471D01*
X1070348Y688724D01*
X1069685Y688850D01*
X1069022Y688597D01*
X1068454Y688093D01*
X1068075Y687335D01*
X1067886Y686325D01*
X1068075Y685315D01*
X1068454Y684557D01*
X1069022Y684052D01*
X1069685Y683800D01*
X1070348Y683926D01*
X1070916Y684305D01*
X1071295Y684810D01*
G01X1075556Y683800D02*
Y688850D01*
G01Y687587D02*
X1075935Y688219D01*
X1076503Y688724D01*
X1077260Y688850D01*
X1077923Y688724D01*
X1078491Y688219D01*
X1078775Y687335D01*
Y683800D01*
G01X1084740Y688850D02*
Y683800D01*
G01Y690870D02*
X1084551Y690996D01*
Y691249D01*
X1084740Y691375D01*
X1084930Y691249D01*
Y690996D01*
X1084740Y690870D01*
G01X1093830Y688219D02*
X1093168Y688724D01*
X1092600Y688850D01*
X1091842Y688597D01*
X1091274Y688093D01*
X1090895Y687209D01*
X1090800Y686325D01*
X1090895Y685441D01*
X1091274Y684684D01*
X1091842Y684052D01*
X1092600Y683800D01*
X1093262Y684052D01*
X1093830Y684557D01*
G01X1101595Y683800D02*
Y688850D01*
G01Y687966D02*
X1101216Y688471D01*
X1100648Y688724D01*
X1099985Y688850D01*
X1099322Y688597D01*
X1098754Y688093D01*
X1098375Y687335D01*
X1098186Y686325D01*
X1098375Y685315D01*
X1098754Y684557D01*
X1099322Y684052D01*
X1099985Y683800D01*
X1100648Y683926D01*
X1101216Y684305D01*
X1101595Y684810D01*
G01X1107465Y683800D02*
Y691375D01*
G01X1124320D02*
Y683800D01*
G01Y684936D02*
X1123941Y684305D01*
X1123373Y683926D01*
X1122710Y683800D01*
X1121953Y684052D01*
X1121385Y684684D01*
X1121006Y685441D01*
X1120911Y686325D01*
X1121006Y687209D01*
X1121385Y687966D01*
X1121953Y688597D01*
X1122710Y688850D01*
X1123373Y688724D01*
X1123846Y688471D01*
X1124320Y687966D01*
G01X1128865Y683800D02*
Y688850D01*
G01Y687840D02*
X1129338Y688345D01*
X1129812Y688724D01*
X1130475Y688850D01*
X1130948Y688724D01*
X1131516Y688345D01*
G01X1139470Y683800D02*
Y688850D01*
G01Y687966D02*
X1139091Y688471D01*
X1138523Y688724D01*
X1137860Y688850D01*
X1137197Y688597D01*
X1136629Y688093D01*
X1136250Y687335D01*
X1136061Y686325D01*
X1136250Y685315D01*
X1136629Y684557D01*
X1137197Y684052D01*
X1137860Y683800D01*
X1138523Y683926D01*
X1139091Y684305D01*
X1139470Y684810D01*
G01X1142973Y688850D02*
X1144110Y683800D01*
X1145340Y688850D01*
X1146571Y683800D01*
X1147708Y688850D01*
G01X1152915D02*
Y683800D01*
G01Y690870D02*
X1152726Y690996D01*
Y691249D01*
X1152915Y691375D01*
X1153105Y691249D01*
Y690996D01*
X1152915Y690870D01*
G01X1158881Y683800D02*
Y688850D01*
G01Y687587D02*
X1159260Y688219D01*
X1159828Y688724D01*
X1160585Y688850D01*
X1161248Y688724D01*
X1161816Y688219D01*
X1162100Y687335D01*
Y683800D01*
G01X1166740Y681906D02*
X1167403Y681401D01*
X1168160Y681275D01*
X1168823Y681401D01*
X1169391Y682032D01*
X1169770Y682916D01*
Y688850D01*
G01Y687840D02*
X1169391Y688345D01*
X1168823Y688724D01*
X1168160Y688850D01*
X1167403Y688597D01*
X1166929Y688093D01*
X1166550Y687209D01*
X1166361Y686325D01*
X1166456Y685567D01*
X1166835Y684684D01*
X1167403Y684052D01*
X1168160Y683800D01*
X1168728Y683926D01*
X1169391Y684431D01*
X1169770Y684936D01*
G01X1174978Y681528D02*
X1176303Y683295D01*
Y685062D01*
X1174978D01*
Y683295D01*
X1176303D01*
G01Y686325D02*
Y688093D01*
X1174978D01*
Y686325D01*
X1176303D01*
G01X355604Y679075D02*
X357877D01*
G01X356740D02*
Y671500D01*
G01X355604D02*
X357877D01*
G01X363747D02*
Y677939D01*
X363937Y678570D01*
X364315Y678949D01*
X364884Y679075D01*
X365452Y678823D01*
X365736Y678191D01*
G01X364600Y676045D02*
X362706D01*
G01X379465Y676550D02*
Y671500D01*
G01Y678570D02*
X379276Y678696D01*
Y678949D01*
X379465Y679075D01*
X379655Y678949D01*
Y678696D01*
X379465Y678570D01*
G01X385620Y672384D02*
X386094Y671879D01*
X386756Y671500D01*
X387325D01*
X387893Y671752D01*
X388271Y672131D01*
X388461Y672636D01*
X388366Y673394D01*
X387987Y673772D01*
X386283Y674530D01*
X385904Y675414D01*
X386094Y676045D01*
X386472Y676424D01*
X387040Y676550D01*
X387609Y676424D01*
X388177Y676045D01*
G01X400865Y669606D02*
X401528Y669101D01*
X402285Y668975D01*
X402948Y669101D01*
X403516Y669732D01*
X403895Y670616D01*
Y676550D01*
G01Y675540D02*
X403516Y676045D01*
X402948Y676424D01*
X402285Y676550D01*
X401528Y676297D01*
X401054Y675793D01*
X400675Y674909D01*
X400486Y674025D01*
X400581Y673267D01*
X400960Y672384D01*
X401528Y671752D01*
X402285Y671500D01*
X402853Y671626D01*
X403516Y672131D01*
X403895Y672636D01*
G01X408440Y671500D02*
Y676550D01*
G01Y675540D02*
X408913Y676045D01*
X409387Y676424D01*
X410050Y676550D01*
X410523Y676424D01*
X411091Y676045D01*
G01X415920Y674909D02*
X418950D01*
X418666Y675793D01*
X418193Y676297D01*
X417530Y676550D01*
X416867Y676424D01*
X416299Y676045D01*
X415920Y675161D01*
X415731Y674404D01*
Y673646D01*
X415920Y672889D01*
X416394Y672131D01*
X416962Y671626D01*
X417625Y671500D01*
X418287Y671752D01*
X418950Y672510D01*
G01X426620Y671500D02*
Y676550D01*
G01Y675666D02*
X426241Y676171D01*
X425673Y676424D01*
X425010Y676550D01*
X424347Y676297D01*
X423779Y675793D01*
X423400Y675035D01*
X423211Y674025D01*
X423400Y673015D01*
X423779Y672257D01*
X424347Y671752D01*
X425010Y671500D01*
X425673Y671626D01*
X426241Y672005D01*
X426620Y672510D01*
G01X432490Y679075D02*
Y671500D01*
G01X431165Y676550D02*
X433816D01*
G01X438645Y674909D02*
X441675D01*
X441391Y675793D01*
X440918Y676297D01*
X440255Y676550D01*
X439592Y676424D01*
X439024Y676045D01*
X438645Y675161D01*
X438456Y674404D01*
Y673646D01*
X438645Y672889D01*
X439119Y672131D01*
X439687Y671626D01*
X440350Y671500D01*
X441012Y671752D01*
X441675Y672510D01*
G01X446315Y671500D02*
Y676550D01*
G01Y675540D02*
X446788Y676045D01*
X447262Y676424D01*
X447925Y676550D01*
X448398Y676424D01*
X448966Y676045D01*
G01X462790Y679075D02*
Y671500D01*
G01X461465Y676550D02*
X464116D01*
G01X468756Y671500D02*
Y679075D01*
G01Y675414D02*
X469229Y676045D01*
X469703Y676424D01*
X470460Y676550D01*
X471028Y676424D01*
X471691Y675919D01*
X471975Y675161D01*
Y671500D01*
G01X479645D02*
Y676550D01*
G01Y675666D02*
X479266Y676171D01*
X478698Y676424D01*
X478035Y676550D01*
X477372Y676297D01*
X476804Y675793D01*
X476425Y675035D01*
X476236Y674025D01*
X476425Y673015D01*
X476804Y672257D01*
X477372Y671752D01*
X478035Y671500D01*
X478698Y671626D01*
X479266Y672005D01*
X479645Y672510D01*
G01X483906Y671500D02*
Y676550D01*
G01Y675287D02*
X484285Y675919D01*
X484853Y676424D01*
X485610Y676550D01*
X486273Y676424D01*
X486841Y675919D01*
X487125Y675035D01*
Y671500D01*
G01X500665D02*
Y679075D01*
X499529Y677560D01*
G01Y671500D02*
X501802D01*
G01X512975D02*
Y676550D01*
G01Y675161D02*
X513259Y675793D01*
X513732Y676297D01*
X514395Y676550D01*
X515058Y676297D01*
X515531Y675793D01*
X515815Y675161D01*
Y671500D01*
G01Y675161D02*
X516100Y675793D01*
X516573Y676297D01*
X517236Y676550D01*
X517899Y676297D01*
X518372Y675793D01*
X518656Y675035D01*
Y671500D01*
G01X523390Y676550D02*
Y671500D01*
G01Y678570D02*
X523201Y678696D01*
Y678949D01*
X523390Y679075D01*
X523580Y678949D01*
Y678696D01*
X523390Y678570D01*
G01X529545Y672384D02*
X530019Y671879D01*
X530681Y671500D01*
X531250D01*
X531818Y671752D01*
X532196Y672131D01*
X532386Y672636D01*
X532291Y673394D01*
X531912Y673772D01*
X530208Y674530D01*
X529829Y675414D01*
X530019Y676045D01*
X530397Y676424D01*
X530965Y676550D01*
X531534Y676424D01*
X532102Y676045D01*
G01X538351Y670111D02*
X538730Y671752D01*
G01X551986Y668975D02*
Y676550D01*
G01Y675414D02*
X552460Y676045D01*
X552933Y676424D01*
X553690Y676550D01*
X554353Y676424D01*
X555016Y675793D01*
X555300Y674909D01*
X555395Y674025D01*
X555300Y673141D01*
X555016Y672257D01*
X554448Y671752D01*
X553690Y671500D01*
X553028Y671626D01*
X552365Y672005D01*
X551986Y672510D01*
G01X561265Y671500D02*
Y679075D01*
G01X567420Y674909D02*
X570450D01*
X570166Y675793D01*
X569693Y676297D01*
X569030Y676550D01*
X568367Y676424D01*
X567799Y676045D01*
X567420Y675161D01*
X567231Y674404D01*
Y673646D01*
X567420Y672889D01*
X567894Y672131D01*
X568462Y671626D01*
X569125Y671500D01*
X569787Y671752D01*
X570450Y672510D01*
G01X578120Y671500D02*
Y676550D01*
G01Y675666D02*
X577741Y676171D01*
X577173Y676424D01*
X576510Y676550D01*
X575847Y676297D01*
X575279Y675793D01*
X574900Y675035D01*
X574711Y674025D01*
X574900Y673015D01*
X575279Y672257D01*
X575847Y671752D01*
X576510Y671500D01*
X577173Y671626D01*
X577741Y672005D01*
X578120Y672510D01*
G01X582570Y672384D02*
X583044Y671879D01*
X583706Y671500D01*
X584275D01*
X584843Y671752D01*
X585221Y672131D01*
X585411Y672636D01*
X585316Y673394D01*
X584937Y673772D01*
X583233Y674530D01*
X582854Y675414D01*
X583044Y676045D01*
X583422Y676424D01*
X583990Y676550D01*
X584559Y676424D01*
X585127Y676045D01*
G01X590145Y674909D02*
X593175D01*
X592891Y675793D01*
X592418Y676297D01*
X591755Y676550D01*
X591092Y676424D01*
X590524Y676045D01*
X590145Y675161D01*
X589956Y674404D01*
Y673646D01*
X590145Y672889D01*
X590619Y672131D01*
X591187Y671626D01*
X591850Y671500D01*
X592512Y671752D01*
X593175Y672510D01*
G01X606715Y676550D02*
Y671500D01*
G01Y678570D02*
X606526Y678696D01*
Y678949D01*
X606715Y679075D01*
X606905Y678949D01*
Y678696D01*
X606715Y678570D01*
G01X612870Y672384D02*
X613344Y671879D01*
X614006Y671500D01*
X614575D01*
X615143Y671752D01*
X615521Y672131D01*
X615711Y672636D01*
X615616Y673394D01*
X615237Y673772D01*
X613533Y674530D01*
X613154Y675414D01*
X613344Y676045D01*
X613722Y676424D01*
X614290Y676550D01*
X614859Y676424D01*
X615427Y676045D01*
G01X620445Y672384D02*
X620919Y671879D01*
X621581Y671500D01*
X622150D01*
X622718Y671752D01*
X623096Y672131D01*
X623286Y672636D01*
X623191Y673394D01*
X622812Y673772D01*
X621108Y674530D01*
X620729Y675414D01*
X620919Y676045D01*
X621297Y676424D01*
X621865Y676550D01*
X622434Y676424D01*
X623002Y676045D01*
G01X627831Y676550D02*
Y673015D01*
X628210Y672131D01*
X628778Y671626D01*
X629440Y671500D01*
X630103Y671626D01*
X630671Y672131D01*
X631050Y673015D01*
G01Y671500D02*
Y676550D01*
G01X635595Y674909D02*
X638625D01*
X638341Y675793D01*
X637868Y676297D01*
X637205Y676550D01*
X636542Y676424D01*
X635974Y676045D01*
X635595Y675161D01*
X635406Y674404D01*
Y673646D01*
X635595Y672889D01*
X636069Y672131D01*
X636637Y671626D01*
X637300Y671500D01*
X637962Y671752D01*
X638625Y672510D01*
G01X650745Y674909D02*
X653775D01*
X653491Y675793D01*
X653018Y676297D01*
X652355Y676550D01*
X651692Y676424D01*
X651124Y676045D01*
X650745Y675161D01*
X650556Y674404D01*
Y673646D01*
X650745Y672889D01*
X651219Y672131D01*
X651787Y671626D01*
X652450Y671500D01*
X653112Y671752D01*
X653775Y672510D01*
G01X658131Y671500D02*
Y676550D01*
G01Y675287D02*
X658510Y675919D01*
X659078Y676424D01*
X659835Y676550D01*
X660498Y676424D01*
X661066Y675919D01*
X661350Y675035D01*
Y671500D01*
G01X665990Y669606D02*
X666653Y669101D01*
X667410Y668975D01*
X668073Y669101D01*
X668641Y669732D01*
X669020Y670616D01*
Y676550D01*
G01Y675540D02*
X668641Y676045D01*
X668073Y676424D01*
X667410Y676550D01*
X666653Y676297D01*
X666179Y675793D01*
X665800Y674909D01*
X665611Y674025D01*
X665706Y673267D01*
X666085Y672384D01*
X666653Y671752D01*
X667410Y671500D01*
X667978Y671626D01*
X668641Y672131D01*
X669020Y672636D01*
G01X674890Y676550D02*
Y671500D01*
G01Y678570D02*
X674701Y678696D01*
Y678949D01*
X674890Y679075D01*
X675080Y678949D01*
Y678696D01*
X674890Y678570D01*
G01X680856Y671500D02*
Y676550D01*
G01Y675287D02*
X681235Y675919D01*
X681803Y676424D01*
X682560Y676550D01*
X683223Y676424D01*
X683791Y675919D01*
X684075Y675035D01*
Y671500D01*
G01X688620Y674909D02*
X691650D01*
X691366Y675793D01*
X690893Y676297D01*
X690230Y676550D01*
X689567Y676424D01*
X688999Y676045D01*
X688620Y675161D01*
X688431Y674404D01*
Y673646D01*
X688620Y672889D01*
X689094Y672131D01*
X689662Y671626D01*
X690325Y671500D01*
X690987Y671752D01*
X691650Y672510D01*
G01X696195Y674909D02*
X699225D01*
X698941Y675793D01*
X698468Y676297D01*
X697805Y676550D01*
X697142Y676424D01*
X696574Y676045D01*
X696195Y675161D01*
X696006Y674404D01*
Y673646D01*
X696195Y672889D01*
X696669Y672131D01*
X697237Y671626D01*
X697900Y671500D01*
X698562Y671752D01*
X699225Y672510D01*
G01X703865Y671500D02*
Y676550D01*
G01Y675540D02*
X704338Y676045D01*
X704812Y676424D01*
X705475Y676550D01*
X705948Y676424D01*
X706516Y676045D01*
G01X712765Y676550D02*
Y671500D01*
G01Y678570D02*
X712576Y678696D01*
Y678949D01*
X712765Y679075D01*
X712955Y678949D01*
Y678696D01*
X712765Y678570D01*
G01X718731Y671500D02*
Y676550D01*
G01Y675287D02*
X719110Y675919D01*
X719678Y676424D01*
X720435Y676550D01*
X721098Y676424D01*
X721666Y675919D01*
X721950Y675035D01*
Y671500D01*
G01X726590Y669606D02*
X727253Y669101D01*
X728010Y668975D01*
X728673Y669101D01*
X729241Y669732D01*
X729620Y670616D01*
Y676550D01*
G01Y675540D02*
X729241Y676045D01*
X728673Y676424D01*
X728010Y676550D01*
X727253Y676297D01*
X726779Y675793D01*
X726400Y674909D01*
X726211Y674025D01*
X726306Y673267D01*
X726685Y672384D01*
X727253Y671752D01*
X728010Y671500D01*
X728578Y671626D01*
X729241Y672131D01*
X729620Y672636D01*
G01X744770Y668975D02*
Y676550D01*
G01Y675414D02*
X744296Y676045D01*
X743728Y676424D01*
X743065Y676550D01*
X742497Y676424D01*
X741835Y675793D01*
X741456Y674909D01*
X741361Y674025D01*
X741456Y673141D01*
X741835Y672257D01*
X742497Y671626D01*
X743065Y671500D01*
X743728Y671626D01*
X744296Y672005D01*
X744770Y672636D01*
G01X749031Y676550D02*
Y673015D01*
X749410Y672131D01*
X749978Y671626D01*
X750640Y671500D01*
X751303Y671626D01*
X751871Y672131D01*
X752250Y673015D01*
G01Y671500D02*
Y676550D01*
G01X756795Y674909D02*
X759825D01*
X759541Y675793D01*
X759068Y676297D01*
X758405Y676550D01*
X757742Y676424D01*
X757174Y676045D01*
X756795Y675161D01*
X756606Y674404D01*
Y673646D01*
X756795Y672889D01*
X757269Y672131D01*
X757837Y671626D01*
X758500Y671500D01*
X759162Y671752D01*
X759825Y672510D01*
G01X764465Y671500D02*
Y676550D01*
G01Y675540D02*
X764938Y676045D01*
X765412Y676424D01*
X766075Y676550D01*
X766548Y676424D01*
X767116Y676045D01*
G01X771377Y669228D02*
X771945Y668975D01*
X772703Y669228D01*
X773176Y669732D01*
X773555Y670364D01*
X774123Y672384D01*
X775354Y676550D01*
G01X772324D02*
X774123Y672384D01*
G01X780940Y671248D02*
X780751Y671374D01*
Y671626D01*
X780940Y671752D01*
X781130Y671626D01*
Y671374D01*
X780940Y671248D01*
G01X355257Y703175D02*
Y697746D01*
X355636Y696610D01*
X356394Y695852D01*
X357340Y695600D01*
X358287Y695852D01*
X359045Y696610D01*
X359424Y697746D01*
Y703175D01*
G01X363306Y695600D02*
Y700650D01*
G01Y699387D02*
X363685Y700019D01*
X364253Y700524D01*
X365010Y700650D01*
X365673Y700524D01*
X366241Y700019D01*
X366525Y699135D01*
Y695600D01*
G01X372490Y700650D02*
Y695600D01*
G01Y702670D02*
X372301Y702796D01*
Y703049D01*
X372490Y703175D01*
X372680Y703049D01*
Y702796D01*
X372490Y702670D01*
G01X380065Y703175D02*
Y695600D01*
G01X378740Y700650D02*
X381391D01*
G01X396730Y700019D02*
X396068Y700524D01*
X395500Y700650D01*
X394742Y700397D01*
X394174Y699893D01*
X393795Y699009D01*
X393700Y698125D01*
X393795Y697241D01*
X394174Y696484D01*
X394742Y695852D01*
X395500Y695600D01*
X396162Y695852D01*
X396730Y696357D01*
G01X402790Y695600D02*
X402222Y695726D01*
X401654Y696231D01*
X401275Y697115D01*
X401086Y698125D01*
X401275Y699135D01*
X401654Y700019D01*
X402222Y700524D01*
X402790Y700650D01*
X403359Y700524D01*
X403927Y700019D01*
X404305Y699135D01*
X404400Y698125D01*
X404305Y697115D01*
X403927Y696231D01*
X403359Y695726D01*
X402790Y695600D01*
G01X408756D02*
Y700650D01*
G01Y699387D02*
X409135Y700019D01*
X409703Y700524D01*
X410460Y700650D01*
X411123Y700524D01*
X411691Y700019D01*
X411975Y699135D01*
Y695600D01*
G01X416236Y700650D02*
X417940Y695600D01*
X419645Y700650D01*
G01X424095Y699009D02*
X427125D01*
X426841Y699893D01*
X426368Y700397D01*
X425705Y700650D01*
X425042Y700524D01*
X424474Y700145D01*
X424095Y699261D01*
X423906Y698504D01*
Y697746D01*
X424095Y696989D01*
X424569Y696231D01*
X425137Y695726D01*
X425800Y695600D01*
X426462Y695852D01*
X427125Y696610D01*
G01X431765Y695600D02*
Y700650D01*
G01Y699640D02*
X432238Y700145D01*
X432712Y700524D01*
X433375Y700650D01*
X433848Y700524D01*
X434416Y700145D01*
G01X439245Y696484D02*
X439719Y695979D01*
X440381Y695600D01*
X440950D01*
X441518Y695852D01*
X441896Y696231D01*
X442086Y696736D01*
X441991Y697494D01*
X441612Y697872D01*
X439908Y698630D01*
X439529Y699514D01*
X439719Y700145D01*
X440097Y700524D01*
X440665Y700650D01*
X441234Y700524D01*
X441802Y700145D01*
G01X448240Y700650D02*
Y695600D01*
G01Y702670D02*
X448051Y702796D01*
Y703049D01*
X448240Y703175D01*
X448430Y703049D01*
Y702796D01*
X448240Y702670D01*
G01X455815Y695600D02*
X455247Y695726D01*
X454679Y696231D01*
X454300Y697115D01*
X454111Y698125D01*
X454300Y699135D01*
X454679Y700019D01*
X455247Y700524D01*
X455815Y700650D01*
X456384Y700524D01*
X456952Y700019D01*
X457330Y699135D01*
X457425Y698125D01*
X457330Y697115D01*
X456952Y696231D01*
X456384Y695726D01*
X455815Y695600D01*
G01X461781D02*
Y700650D01*
G01Y699387D02*
X462160Y700019D01*
X462728Y700524D01*
X463485Y700650D01*
X464148Y700524D01*
X464716Y700019D01*
X465000Y699135D01*
Y695600D01*
G01X478540Y700650D02*
Y695600D01*
G01Y702670D02*
X478351Y702796D01*
Y703049D01*
X478540Y703175D01*
X478730Y703049D01*
Y702796D01*
X478540Y702670D01*
G01X484695Y696484D02*
X485169Y695979D01*
X485831Y695600D01*
X486400D01*
X486968Y695852D01*
X487346Y696231D01*
X487536Y696736D01*
X487441Y697494D01*
X487062Y697872D01*
X485358Y698630D01*
X484979Y699514D01*
X485169Y700145D01*
X485547Y700524D01*
X486115Y700650D01*
X486684Y700524D01*
X487252Y700145D01*
G01X492270Y696484D02*
X492744Y695979D01*
X493406Y695600D01*
X493975D01*
X494543Y695852D01*
X494921Y696231D01*
X495111Y696736D01*
X495016Y697494D01*
X494637Y697872D01*
X492933Y698630D01*
X492554Y699514D01*
X492744Y700145D01*
X493122Y700524D01*
X493690Y700650D01*
X494259Y700524D01*
X494827Y700145D01*
G01X499656Y700650D02*
Y697115D01*
X500035Y696231D01*
X500603Y695726D01*
X501265Y695600D01*
X501928Y695726D01*
X502496Y696231D01*
X502875Y697115D01*
G01Y695600D02*
Y700650D01*
G01X507420Y699009D02*
X510450D01*
X510166Y699893D01*
X509693Y700397D01*
X509030Y700650D01*
X508367Y700524D01*
X507799Y700145D01*
X507420Y699261D01*
X507231Y698504D01*
Y697746D01*
X507420Y696989D01*
X507894Y696231D01*
X508462Y695726D01*
X509125Y695600D01*
X509787Y695852D01*
X510450Y696610D01*
G01X516415Y695348D02*
X516226Y695474D01*
Y695726D01*
X516415Y695852D01*
X516605Y695726D01*
Y695474D01*
X516415Y695348D01*
G01Y698756D02*
X516226Y698882D01*
Y699135D01*
X516415Y699261D01*
X516605Y699135D01*
Y698882D01*
X516415Y698756D01*
G01X361340Y735000D02*
Y742575D01*
X360204Y741060D01*
G01Y735000D02*
X362477D01*
G01X368915D02*
Y742575D01*
X367779Y741060D01*
G01Y735000D02*
X370052D01*
G01X360840Y747500D02*
Y755075D01*
X359704Y753560D01*
G01Y747500D02*
X361977D01*
G01X368415Y755075D02*
X367658Y754823D01*
X367090Y754191D01*
X366711Y753434D01*
X366427Y752424D01*
X366332Y751287D01*
X366427Y750151D01*
X366711Y749141D01*
X367090Y748384D01*
X367658Y747752D01*
X368415Y747500D01*
X369173Y747752D01*
X369741Y748384D01*
X370120Y749141D01*
X370404Y750151D01*
X370499Y751287D01*
X370404Y752424D01*
X370120Y753434D01*
X369741Y754191D01*
X369173Y754823D01*
X368415Y755075D01*
G01X363731Y761384D02*
X364394Y760752D01*
X365151Y760500D01*
X365909Y760752D01*
X366571Y761510D01*
X367045Y762646D01*
X367234Y763782D01*
Y765171D01*
X367045Y766307D01*
X366571Y767317D01*
X366003Y767823D01*
X365340Y768075D01*
X364583Y767823D01*
X364015Y767317D01*
X363636Y766560D01*
X363447Y765550D01*
X363636Y764666D01*
X364110Y763782D01*
X364678Y763277D01*
X365340Y763151D01*
X366098Y763404D01*
X366666Y764035D01*
X367234Y765171D01*
G01X365151Y785000D02*
X365340Y786641D01*
X365625Y788030D01*
X366003Y789293D01*
X366477Y790681D01*
X367234Y792575D01*
X363447D01*
G01X365340Y773000D02*
X366003Y773126D01*
X366761Y773505D01*
X367234Y774136D01*
X367424Y775020D01*
X367234Y775904D01*
X366666Y776661D01*
X365814Y777040D01*
X364867D01*
X364299Y777293D01*
X363825Y777924D01*
X363636Y778807D01*
X363920Y779691D01*
X364583Y780323D01*
X365340Y780575D01*
X366098Y780323D01*
X366761Y779691D01*
X367045Y778807D01*
X366855Y777924D01*
X366382Y777293D01*
X365814Y777040D01*
X364867D01*
X364015Y776661D01*
X363447Y775904D01*
X363257Y775020D01*
X363447Y774136D01*
X363920Y773505D01*
X364678Y773126D01*
X365340Y773000D01*
G01X364041Y801156D02*
X364704Y802040D01*
X365272Y802545D01*
X366030Y802797D01*
X366693Y802545D01*
X367166Y802040D01*
X367545Y801282D01*
X367640Y800399D01*
X367545Y799641D01*
X367166Y798884D01*
X366598Y798252D01*
X365935Y798000D01*
X365178Y798252D01*
X364515Y799010D01*
X364136Y800146D01*
X364041Y801409D01*
X364231Y803050D01*
X364515Y803934D01*
X364988Y804817D01*
X365651Y805449D01*
X366314Y805575D01*
X366977Y805323D01*
X367450Y804691D01*
G01X366977Y836000D02*
Y843575D01*
X363473Y838146D01*
X368208D01*
G01X363757Y818636D02*
X364325Y818005D01*
X364988Y817626D01*
X365840Y817500D01*
X366693Y817752D01*
X367355Y818257D01*
X367829Y819141D01*
X367924Y820151D01*
X367734Y821161D01*
X367261Y821793D01*
X366598Y822297D01*
X365935Y822424D01*
X365272Y822297D01*
X364420Y821793D01*
X364704Y825075D01*
X367261D01*
G01X363757Y861515D02*
X364325Y860631D01*
X365083Y860126D01*
X365935Y860000D01*
X366693Y860126D01*
X367450Y860757D01*
X367924Y861515D01*
X368018Y862272D01*
X367829Y863156D01*
X367166Y863787D01*
X366503Y864040D01*
X365651D01*
G01X366503D02*
X367071Y864419D01*
X367545Y865050D01*
X367734Y865807D01*
X367545Y866565D01*
X367071Y867196D01*
X366219Y867575D01*
X365367Y867449D01*
X364515Y866944D01*
G01X364541Y879313D02*
X365110Y880070D01*
X365772Y880449D01*
X366530Y880575D01*
X367477Y880323D01*
X368140Y879691D01*
X368329Y878934D01*
X368234Y878176D01*
X367855Y877545D01*
X365962Y876282D01*
X365110Y875399D01*
X364541Y874136D01*
X364352Y873000D01*
X368329D01*
G01X366340Y885500D02*
Y893075D01*
X365204Y891560D01*
G01Y885500D02*
X367477D01*
G01X356663Y901000D02*
Y908575D01*
X361018Y901000D01*
Y908575D01*
G01X366415Y901000D02*
X365658Y901126D01*
X364995Y901631D01*
X364427Y902389D01*
X364048Y903272D01*
X363859Y904282D01*
Y905293D01*
X364048Y906303D01*
X364427Y907186D01*
X364995Y907944D01*
X365658Y908449D01*
X366415Y908575D01*
X367173Y908449D01*
X367836Y907944D01*
X368404Y907186D01*
X368783Y906303D01*
X368972Y905293D01*
Y904282D01*
X368783Y903272D01*
X368404Y902389D01*
X367836Y901631D01*
X367173Y901126D01*
X366415Y901000D01*
G01X373990Y900748D02*
X373801Y900874D01*
Y901126D01*
X373990Y901252D01*
X374180Y901126D01*
Y900874D01*
X373990Y900748D01*
G01X382852Y885000D02*
Y892575D01*
G01X386829D02*
Y885000D01*
G01Y888787D02*
X382852D01*
G01X392415Y885000D02*
X391847Y885126D01*
X391279Y885631D01*
X390900Y886515D01*
X390711Y887525D01*
X390900Y888535D01*
X391279Y889419D01*
X391847Y889924D01*
X392415Y890050D01*
X392984Y889924D01*
X393552Y889419D01*
X393930Y888535D01*
X394025Y887525D01*
X393930Y886515D01*
X393552Y885631D01*
X392984Y885126D01*
X392415Y885000D01*
G01X399990D02*
Y892575D01*
G01X406145Y888409D02*
X409175D01*
X408891Y889293D01*
X408418Y889797D01*
X407755Y890050D01*
X407092Y889924D01*
X406524Y889545D01*
X406145Y888661D01*
X405956Y887904D01*
Y887146D01*
X406145Y886389D01*
X406619Y885631D01*
X407187Y885126D01*
X407850Y885000D01*
X408512Y885252D01*
X409175Y886010D01*
G01X413040Y644675D02*
Y637100D01*
G01X410863Y644675D02*
X415218D01*
G01X419006Y637100D02*
Y644675D01*
G01Y641014D02*
X419479Y641645D01*
X419953Y642024D01*
X420710Y642150D01*
X421278Y642024D01*
X421941Y641519D01*
X422225Y640761D01*
Y637100D01*
G01X426770Y640509D02*
X429800D01*
X429516Y641393D01*
X429043Y641897D01*
X428380Y642150D01*
X427717Y642024D01*
X427149Y641645D01*
X426770Y640761D01*
X426581Y640004D01*
Y639246D01*
X426770Y638489D01*
X427244Y637731D01*
X427812Y637226D01*
X428475Y637100D01*
X429137Y637352D01*
X429800Y638110D01*
G01X434440Y637100D02*
Y642150D01*
G01Y641140D02*
X434913Y641645D01*
X435387Y642024D01*
X436050Y642150D01*
X436523Y642024D01*
X437091Y641645D01*
G01X441920Y640509D02*
X444950D01*
X444666Y641393D01*
X444193Y641897D01*
X443530Y642150D01*
X442867Y642024D01*
X442299Y641645D01*
X441920Y640761D01*
X441731Y640004D01*
Y639246D01*
X441920Y638489D01*
X442394Y637731D01*
X442962Y637226D01*
X443625Y637100D01*
X444287Y637352D01*
X444950Y638110D01*
G01X450347Y637100D02*
Y643539D01*
X450537Y644170D01*
X450915Y644549D01*
X451484Y644675D01*
X452052Y644423D01*
X452336Y643791D01*
G01X451200Y641645D02*
X449306D01*
G01X458490Y637100D02*
X457922Y637226D01*
X457354Y637731D01*
X456975Y638615D01*
X456786Y639625D01*
X456975Y640635D01*
X457354Y641519D01*
X457922Y642024D01*
X458490Y642150D01*
X459059Y642024D01*
X459627Y641519D01*
X460005Y640635D01*
X460100Y639625D01*
X460005Y638615D01*
X459627Y637731D01*
X459059Y637226D01*
X458490Y637100D01*
G01X464740D02*
Y642150D01*
G01Y641140D02*
X465213Y641645D01*
X465687Y642024D01*
X466350Y642150D01*
X466823Y642024D01*
X467391Y641645D01*
G01X472220Y640509D02*
X475250D01*
X474966Y641393D01*
X474493Y641897D01*
X473830Y642150D01*
X473167Y642024D01*
X472599Y641645D01*
X472220Y640761D01*
X472031Y640004D01*
Y639246D01*
X472220Y638489D01*
X472694Y637731D01*
X473262Y637226D01*
X473925Y637100D01*
X474587Y637352D01*
X475250Y638110D01*
G01X481026Y635711D02*
X481405Y637352D01*
G01X494661Y634575D02*
Y642150D01*
G01Y641014D02*
X495135Y641645D01*
X495608Y642024D01*
X496365Y642150D01*
X497028Y642024D01*
X497691Y641393D01*
X497975Y640509D01*
X498070Y639625D01*
X497975Y638741D01*
X497691Y637857D01*
X497123Y637352D01*
X496365Y637100D01*
X495703Y637226D01*
X495040Y637605D01*
X494661Y638110D01*
G01X503940Y637100D02*
Y644675D01*
G01X510095Y640509D02*
X513125D01*
X512841Y641393D01*
X512368Y641897D01*
X511705Y642150D01*
X511042Y642024D01*
X510474Y641645D01*
X510095Y640761D01*
X509906Y640004D01*
Y639246D01*
X510095Y638489D01*
X510569Y637731D01*
X511137Y637226D01*
X511800Y637100D01*
X512462Y637352D01*
X513125Y638110D01*
G01X520795Y637100D02*
Y642150D01*
G01Y641266D02*
X520416Y641771D01*
X519848Y642024D01*
X519185Y642150D01*
X518522Y641897D01*
X517954Y641393D01*
X517575Y640635D01*
X517386Y639625D01*
X517575Y638615D01*
X517954Y637857D01*
X518522Y637352D01*
X519185Y637100D01*
X519848Y637226D01*
X520416Y637605D01*
X520795Y638110D01*
G01X525245Y637984D02*
X525719Y637479D01*
X526381Y637100D01*
X526950D01*
X527518Y637352D01*
X527896Y637731D01*
X528086Y638236D01*
X527991Y638994D01*
X527612Y639372D01*
X525908Y640130D01*
X525529Y641014D01*
X525719Y641645D01*
X526097Y642024D01*
X526665Y642150D01*
X527234Y642024D01*
X527802Y641645D01*
G01X532820Y640509D02*
X535850D01*
X535566Y641393D01*
X535093Y641897D01*
X534430Y642150D01*
X533767Y642024D01*
X533199Y641645D01*
X532820Y640761D01*
X532631Y640004D01*
Y639246D01*
X532820Y638489D01*
X533294Y637731D01*
X533862Y637226D01*
X534525Y637100D01*
X535187Y637352D01*
X535850Y638110D01*
G01X548822Y637100D02*
Y643539D01*
X549012Y644170D01*
X549390Y644549D01*
X549959Y644675D01*
X550527Y644423D01*
X550811Y643791D01*
G01X549675Y641645D02*
X547781D01*
G01X556965Y637100D02*
X556397Y637226D01*
X555829Y637731D01*
X555450Y638615D01*
X555261Y639625D01*
X555450Y640635D01*
X555829Y641519D01*
X556397Y642024D01*
X556965Y642150D01*
X557534Y642024D01*
X558102Y641519D01*
X558480Y640635D01*
X558575Y639625D01*
X558480Y638615D01*
X558102Y637731D01*
X557534Y637226D01*
X556965Y637100D01*
G01X564540D02*
Y644675D01*
G01X572115Y637100D02*
Y644675D01*
G01X579690Y637100D02*
X579122Y637226D01*
X578554Y637731D01*
X578175Y638615D01*
X577986Y639625D01*
X578175Y640635D01*
X578554Y641519D01*
X579122Y642024D01*
X579690Y642150D01*
X580259Y642024D01*
X580827Y641519D01*
X581205Y640635D01*
X581300Y639625D01*
X581205Y638615D01*
X580827Y637731D01*
X580259Y637226D01*
X579690Y637100D01*
G01X584898Y642150D02*
X586035Y637100D01*
X587265Y642150D01*
X588496Y637100D01*
X589633Y642150D01*
G01X600332Y638615D02*
X600900Y637731D01*
X601658Y637226D01*
X602510Y637100D01*
X603268Y637226D01*
X604025Y637857D01*
X604499Y638615D01*
X604593Y639372D01*
X604404Y640256D01*
X603741Y640887D01*
X603078Y641140D01*
X602226D01*
G01X603078D02*
X603646Y641519D01*
X604120Y642150D01*
X604309Y642907D01*
X604120Y643665D01*
X603646Y644296D01*
X602794Y644675D01*
X601942Y644549D01*
X601090Y644044D01*
G01X609990Y636848D02*
X609801Y636974D01*
Y637226D01*
X609990Y637352D01*
X610180Y637226D01*
Y636974D01*
X609990Y636848D01*
G01X617565Y637100D02*
Y644675D01*
X616429Y643160D01*
G01Y637100D02*
X618702D01*
G01X625140D02*
X625803Y637226D01*
X626561Y637605D01*
X627034Y638236D01*
X627224Y639120D01*
X627034Y640004D01*
X626466Y640761D01*
X625614Y641140D01*
X624667D01*
X624099Y641393D01*
X623625Y642024D01*
X623436Y642907D01*
X623720Y643791D01*
X624383Y644423D01*
X625140Y644675D01*
X625898Y644423D01*
X626561Y643791D01*
X626845Y642907D01*
X626655Y642024D01*
X626182Y641393D01*
X625614Y641140D01*
X624667D01*
X623815Y640761D01*
X623247Y640004D01*
X623057Y639120D01*
X623247Y638236D01*
X623720Y637605D01*
X624478Y637226D01*
X625140Y637100D01*
G01X629875D02*
Y642150D01*
G01Y640761D02*
X630159Y641393D01*
X630632Y641897D01*
X631295Y642150D01*
X631958Y641897D01*
X632431Y641393D01*
X632715Y640761D01*
Y637100D01*
G01Y640761D02*
X633000Y641393D01*
X633473Y641897D01*
X634136Y642150D01*
X634799Y641897D01*
X635272Y641393D01*
X635556Y640635D01*
Y637100D01*
G01X637450D02*
Y642150D01*
G01Y640761D02*
X637734Y641393D01*
X638207Y641897D01*
X638870Y642150D01*
X639533Y641897D01*
X640006Y641393D01*
X640290Y640761D01*
Y637100D01*
G01Y640761D02*
X640575Y641393D01*
X641048Y641897D01*
X641711Y642150D01*
X642374Y641897D01*
X642847Y641393D01*
X643131Y640635D01*
Y637100D01*
G01X655440Y644675D02*
Y637100D01*
G01X654115Y642150D02*
X656766D01*
G01X663015Y637100D02*
X662447Y637226D01*
X661879Y637731D01*
X661500Y638615D01*
X661311Y639625D01*
X661500Y640635D01*
X661879Y641519D01*
X662447Y642024D01*
X663015Y642150D01*
X663584Y642024D01*
X664152Y641519D01*
X664530Y640635D01*
X664625Y639625D01*
X664530Y638615D01*
X664152Y637731D01*
X663584Y637226D01*
X663015Y637100D01*
G01X676461Y634575D02*
Y642150D01*
G01Y641014D02*
X676935Y641645D01*
X677408Y642024D01*
X678165Y642150D01*
X678828Y642024D01*
X679491Y641393D01*
X679775Y640509D01*
X679870Y639625D01*
X679775Y638741D01*
X679491Y637857D01*
X678923Y637352D01*
X678165Y637100D01*
X677503Y637226D01*
X676840Y637605D01*
X676461Y638110D01*
G01X684415Y637100D02*
Y642150D01*
G01Y641140D02*
X684888Y641645D01*
X685362Y642024D01*
X686025Y642150D01*
X686498Y642024D01*
X687066Y641645D01*
G01X693315Y637100D02*
X692747Y637226D01*
X692179Y637731D01*
X691800Y638615D01*
X691611Y639625D01*
X691800Y640635D01*
X692179Y641519D01*
X692747Y642024D01*
X693315Y642150D01*
X693884Y642024D01*
X694452Y641519D01*
X694830Y640635D01*
X694925Y639625D01*
X694830Y638615D01*
X694452Y637731D01*
X693884Y637226D01*
X693315Y637100D01*
G01X702595Y644675D02*
Y637100D01*
G01Y638236D02*
X702216Y637605D01*
X701648Y637226D01*
X700985Y637100D01*
X700228Y637352D01*
X699660Y637984D01*
X699281Y638741D01*
X699186Y639625D01*
X699281Y640509D01*
X699660Y641266D01*
X700228Y641897D01*
X700985Y642150D01*
X701648Y642024D01*
X702121Y641771D01*
X702595Y641266D01*
G01X706856Y642150D02*
Y638615D01*
X707235Y637731D01*
X707803Y637226D01*
X708465Y637100D01*
X709128Y637226D01*
X709696Y637731D01*
X710075Y638615D01*
G01Y637100D02*
Y642150D01*
G01X717555Y641519D02*
X716893Y642024D01*
X716325Y642150D01*
X715567Y641897D01*
X714999Y641393D01*
X714620Y640509D01*
X714525Y639625D01*
X714620Y638741D01*
X714999Y637984D01*
X715567Y637352D01*
X716325Y637100D01*
X716987Y637352D01*
X717555Y637857D01*
G01X722195Y640509D02*
X725225D01*
X724941Y641393D01*
X724468Y641897D01*
X723805Y642150D01*
X723142Y642024D01*
X722574Y641645D01*
X722195Y640761D01*
X722006Y640004D01*
Y639246D01*
X722195Y638489D01*
X722669Y637731D01*
X723237Y637226D01*
X723900Y637100D01*
X724562Y637352D01*
X725225Y638110D01*
G01X738765Y644675D02*
Y637100D01*
G01X737440Y642150D02*
X740091D01*
G01X744731Y637100D02*
Y644675D01*
G01Y641014D02*
X745204Y641645D01*
X745678Y642024D01*
X746435Y642150D01*
X747003Y642024D01*
X747666Y641519D01*
X747950Y640761D01*
Y637100D01*
G01X753915Y642150D02*
Y637100D01*
G01Y644170D02*
X753726Y644296D01*
Y644549D01*
X753915Y644675D01*
X754105Y644549D01*
Y644296D01*
X753915Y644170D01*
G01X760070Y637984D02*
X760544Y637479D01*
X761206Y637100D01*
X761775D01*
X762343Y637352D01*
X762721Y637731D01*
X762911Y638236D01*
X762816Y638994D01*
X762437Y639372D01*
X760733Y640130D01*
X760354Y641014D01*
X760544Y641645D01*
X760922Y642024D01*
X761490Y642150D01*
X762059Y642024D01*
X762627Y641645D01*
G01X774936Y637100D02*
Y644675D01*
G01Y640887D02*
X775410Y641645D01*
X775978Y642024D01*
X776546Y642150D01*
X777398Y641897D01*
X777966Y641393D01*
X778345Y640509D01*
Y639499D01*
X778155Y638489D01*
X777777Y637731D01*
X777114Y637226D01*
X776546Y637100D01*
X775978Y637226D01*
X775410Y637605D01*
X774936Y638236D01*
G01X784215Y637100D02*
X783647Y637226D01*
X783079Y637731D01*
X782700Y638615D01*
X782511Y639625D01*
X782700Y640635D01*
X783079Y641519D01*
X783647Y642024D01*
X784215Y642150D01*
X784784Y642024D01*
X785352Y641519D01*
X785730Y640635D01*
X785825Y639625D01*
X785730Y638615D01*
X785352Y637731D01*
X784784Y637226D01*
X784215Y637100D01*
G01X793495D02*
Y642150D01*
G01Y641266D02*
X793116Y641771D01*
X792548Y642024D01*
X791885Y642150D01*
X791222Y641897D01*
X790654Y641393D01*
X790275Y640635D01*
X790086Y639625D01*
X790275Y638615D01*
X790654Y637857D01*
X791222Y637352D01*
X791885Y637100D01*
X792548Y637226D01*
X793116Y637605D01*
X793495Y638110D01*
G01X798040Y637100D02*
Y642150D01*
G01Y641140D02*
X798513Y641645D01*
X798987Y642024D01*
X799650Y642150D01*
X800123Y642024D01*
X800691Y641645D01*
G01X808645Y644675D02*
Y637100D01*
G01Y638236D02*
X808266Y637605D01*
X807698Y637226D01*
X807035Y637100D01*
X806278Y637352D01*
X805710Y637984D01*
X805331Y638741D01*
X805236Y639625D01*
X805331Y640509D01*
X805710Y641266D01*
X806278Y641897D01*
X807035Y642150D01*
X807698Y642024D01*
X808171Y641771D01*
X808645Y641266D01*
G01X814515Y636848D02*
X814326Y636974D01*
Y637226D01*
X814515Y637352D01*
X814705Y637226D01*
Y636974D01*
X814515Y636848D01*
G01X412840Y654675D02*
Y647100D01*
G01X410663Y654675D02*
X415018D01*
G01X418806Y647100D02*
Y654675D01*
G01Y651014D02*
X419279Y651645D01*
X419753Y652024D01*
X420510Y652150D01*
X421078Y652024D01*
X421741Y651519D01*
X422025Y650761D01*
Y647100D01*
G01X426570Y650509D02*
X429600D01*
X429316Y651393D01*
X428843Y651897D01*
X428180Y652150D01*
X427517Y652024D01*
X426949Y651645D01*
X426570Y650761D01*
X426381Y650004D01*
Y649246D01*
X426570Y648489D01*
X427044Y647731D01*
X427612Y647226D01*
X428275Y647100D01*
X428937Y647352D01*
X429600Y648110D01*
G01X433956Y647100D02*
Y652150D01*
G01Y650887D02*
X434335Y651519D01*
X434903Y652024D01*
X435660Y652150D01*
X436323Y652024D01*
X436891Y651519D01*
X437175Y650635D01*
Y647100D01*
G01X452230Y651519D02*
X451568Y652024D01*
X451000Y652150D01*
X450242Y651897D01*
X449674Y651393D01*
X449295Y650509D01*
X449200Y649625D01*
X449295Y648741D01*
X449674Y647984D01*
X450242Y647352D01*
X451000Y647100D01*
X451662Y647352D01*
X452230Y647857D01*
G01X458290Y647100D02*
X457722Y647226D01*
X457154Y647731D01*
X456775Y648615D01*
X456586Y649625D01*
X456775Y650635D01*
X457154Y651519D01*
X457722Y652024D01*
X458290Y652150D01*
X458859Y652024D01*
X459427Y651519D01*
X459805Y650635D01*
X459900Y649625D01*
X459805Y648615D01*
X459427Y647731D01*
X458859Y647226D01*
X458290Y647100D01*
G01X464256D02*
Y652150D01*
G01Y650887D02*
X464635Y651519D01*
X465203Y652024D01*
X465960Y652150D01*
X466623Y652024D01*
X467191Y651519D01*
X467475Y650635D01*
Y647100D01*
G01X471736Y652150D02*
X473440Y647100D01*
X475145Y652150D01*
G01X479595Y650509D02*
X482625D01*
X482341Y651393D01*
X481868Y651897D01*
X481205Y652150D01*
X480542Y652024D01*
X479974Y651645D01*
X479595Y650761D01*
X479406Y650004D01*
Y649246D01*
X479595Y648489D01*
X480069Y647731D01*
X480637Y647226D01*
X481300Y647100D01*
X481962Y647352D01*
X482625Y648110D01*
G01X487265Y647100D02*
Y652150D01*
G01Y651140D02*
X487738Y651645D01*
X488212Y652024D01*
X488875Y652150D01*
X489348Y652024D01*
X489916Y651645D01*
G01X496165Y654675D02*
Y647100D01*
G01X494840Y652150D02*
X497491D01*
G01X509232Y648615D02*
X509800Y647731D01*
X510558Y647226D01*
X511410Y647100D01*
X512168Y647226D01*
X512925Y647857D01*
X513399Y648615D01*
X513493Y649372D01*
X513304Y650256D01*
X512641Y650887D01*
X511978Y651140D01*
X511126D01*
G01X511978D02*
X512546Y651519D01*
X513020Y652150D01*
X513209Y652907D01*
X513020Y653665D01*
X512546Y654296D01*
X511694Y654675D01*
X510842Y654549D01*
X509990Y654044D01*
G01X518890Y646848D02*
X518701Y646974D01*
Y647226D01*
X518890Y647352D01*
X519080Y647226D01*
Y646974D01*
X518890Y646848D01*
G01X526465Y647100D02*
Y654675D01*
X525329Y653160D01*
G01Y647100D02*
X527602D01*
G01X534040D02*
X534703Y647226D01*
X535461Y647605D01*
X535934Y648236D01*
X536124Y649120D01*
X535934Y650004D01*
X535366Y650761D01*
X534514Y651140D01*
X533567D01*
X532999Y651393D01*
X532525Y652024D01*
X532336Y652907D01*
X532620Y653791D01*
X533283Y654423D01*
X534040Y654675D01*
X534798Y654423D01*
X535461Y653791D01*
X535745Y652907D01*
X535555Y652024D01*
X535082Y651393D01*
X534514Y651140D01*
X533567D01*
X532715Y650761D01*
X532147Y650004D01*
X531957Y649120D01*
X532147Y648236D01*
X532620Y647605D01*
X533378Y647226D01*
X534040Y647100D01*
G01X538775D02*
Y652150D01*
G01Y650761D02*
X539059Y651393D01*
X539532Y651897D01*
X540195Y652150D01*
X540858Y651897D01*
X541331Y651393D01*
X541615Y650761D01*
Y647100D01*
G01Y650761D02*
X541900Y651393D01*
X542373Y651897D01*
X543036Y652150D01*
X543699Y651897D01*
X544172Y651393D01*
X544456Y650635D01*
Y647100D01*
G01X546350D02*
Y652150D01*
G01Y650761D02*
X546634Y651393D01*
X547107Y651897D01*
X547770Y652150D01*
X548433Y651897D01*
X548906Y651393D01*
X549190Y650761D01*
Y647100D01*
G01Y650761D02*
X549475Y651393D01*
X549948Y651897D01*
X550611Y652150D01*
X551274Y651897D01*
X551747Y651393D01*
X552031Y650635D01*
Y647100D01*
G01X564340Y652150D02*
Y647100D01*
G01Y654170D02*
X564151Y654296D01*
Y654549D01*
X564340Y654675D01*
X564530Y654549D01*
Y654296D01*
X564340Y654170D01*
G01X570306Y647100D02*
Y652150D01*
G01Y650887D02*
X570685Y651519D01*
X571253Y652024D01*
X572010Y652150D01*
X572673Y652024D01*
X573241Y651519D01*
X573525Y650635D01*
Y647100D01*
G01X579490Y654675D02*
Y647100D01*
G01X578165Y652150D02*
X580816D01*
G01X587065Y647100D02*
X586497Y647226D01*
X585929Y647731D01*
X585550Y648615D01*
X585361Y649625D01*
X585550Y650635D01*
X585929Y651519D01*
X586497Y652024D01*
X587065Y652150D01*
X587634Y652024D01*
X588202Y651519D01*
X588580Y650635D01*
X588675Y649625D01*
X588580Y648615D01*
X588202Y647731D01*
X587634Y647226D01*
X587065Y647100D01*
G01X602215D02*
Y654675D01*
X601079Y653160D01*
G01Y647100D02*
X603352D01*
G01X607991Y653413D02*
X608560Y654170D01*
X609222Y654549D01*
X609980Y654675D01*
X610927Y654423D01*
X611590Y653791D01*
X611779Y653034D01*
X611684Y652276D01*
X611305Y651645D01*
X609412Y650382D01*
X608560Y649499D01*
X607991Y648236D01*
X607802Y647100D01*
X611779D01*
G01X615282Y648236D02*
X615850Y647605D01*
X616513Y647226D01*
X617365Y647100D01*
X618218Y647352D01*
X618880Y647857D01*
X619354Y648741D01*
X619449Y649751D01*
X619259Y650761D01*
X618786Y651393D01*
X618123Y651897D01*
X617460Y652024D01*
X616797Y651897D01*
X615945Y651393D01*
X616229Y654675D01*
X618786D01*
G01X624940Y646848D02*
X624751Y646974D01*
Y647226D01*
X624940Y647352D01*
X625130Y647226D01*
Y646974D01*
X624940Y646848D01*
G01X632515Y647100D02*
Y654675D01*
X631379Y653160D01*
G01Y647100D02*
X633652D01*
G01X638481Y647984D02*
X639144Y647352D01*
X639901Y647100D01*
X640659Y647352D01*
X641321Y648110D01*
X641795Y649246D01*
X641984Y650382D01*
Y651771D01*
X641795Y652907D01*
X641321Y653917D01*
X640753Y654423D01*
X640090Y654675D01*
X639333Y654423D01*
X638765Y653917D01*
X638386Y653160D01*
X638197Y652150D01*
X638386Y651266D01*
X638860Y650382D01*
X639428Y649877D01*
X640090Y649751D01*
X640848Y650004D01*
X641416Y650635D01*
X641984Y651771D01*
G01X645866Y650256D02*
X646529Y651140D01*
X647097Y651645D01*
X647855Y651897D01*
X648518Y651645D01*
X648991Y651140D01*
X649370Y650382D01*
X649465Y649499D01*
X649370Y648741D01*
X648991Y647984D01*
X648423Y647352D01*
X647760Y647100D01*
X647003Y647352D01*
X646340Y648110D01*
X645961Y649246D01*
X645866Y650509D01*
X646056Y652150D01*
X646340Y653034D01*
X646813Y653917D01*
X647476Y654549D01*
X648139Y654675D01*
X648802Y654423D01*
X649275Y653791D01*
G01X655240Y647100D02*
X655903Y647226D01*
X656661Y647605D01*
X657134Y648236D01*
X657324Y649120D01*
X657134Y650004D01*
X656566Y650761D01*
X655714Y651140D01*
X654767D01*
X654199Y651393D01*
X653725Y652024D01*
X653536Y652907D01*
X653820Y653791D01*
X654483Y654423D01*
X655240Y654675D01*
X655998Y654423D01*
X656661Y653791D01*
X656945Y652907D01*
X656755Y652024D01*
X656282Y651393D01*
X655714Y651140D01*
X654767D01*
X653915Y650761D01*
X653347Y650004D01*
X653157Y649120D01*
X653347Y648236D01*
X653820Y647605D01*
X654578Y647226D01*
X655240Y647100D01*
G01X659975D02*
Y652150D01*
G01Y650761D02*
X660259Y651393D01*
X660732Y651897D01*
X661395Y652150D01*
X662058Y651897D01*
X662531Y651393D01*
X662815Y650761D01*
Y647100D01*
G01Y650761D02*
X663100Y651393D01*
X663573Y651897D01*
X664236Y652150D01*
X664899Y651897D01*
X665372Y651393D01*
X665656Y650635D01*
Y647100D01*
G01X670390Y652150D02*
Y647100D01*
G01Y654170D02*
X670201Y654296D01*
Y654549D01*
X670390Y654675D01*
X670580Y654549D01*
Y654296D01*
X670390Y654170D01*
G01X677965Y647100D02*
Y654675D01*
G01X685351Y645711D02*
X685730Y647352D01*
G01X700690Y654675D02*
Y647100D01*
G01X699365Y652150D02*
X702016D01*
G01X706656Y647100D02*
Y654675D01*
G01Y651014D02*
X707129Y651645D01*
X707603Y652024D01*
X708360Y652150D01*
X708928Y652024D01*
X709591Y651519D01*
X709875Y650761D01*
Y647100D01*
G01X714420Y650509D02*
X717450D01*
X717166Y651393D01*
X716693Y651897D01*
X716030Y652150D01*
X715367Y652024D01*
X714799Y651645D01*
X714420Y650761D01*
X714231Y650004D01*
Y649246D01*
X714420Y648489D01*
X714894Y647731D01*
X715462Y647226D01*
X716125Y647100D01*
X716787Y647352D01*
X717450Y648110D01*
G01X732695Y654675D02*
Y647100D01*
G01Y648236D02*
X732316Y647605D01*
X731748Y647226D01*
X731085Y647100D01*
X730328Y647352D01*
X729760Y647984D01*
X729381Y648741D01*
X729286Y649625D01*
X729381Y650509D01*
X729760Y651266D01*
X730328Y651897D01*
X731085Y652150D01*
X731748Y652024D01*
X732221Y651771D01*
X732695Y651266D01*
G01X738565Y652150D02*
Y647100D01*
G01Y654170D02*
X738376Y654296D01*
Y654549D01*
X738565Y654675D01*
X738755Y654549D01*
Y654296D01*
X738565Y654170D01*
G01X745572Y647100D02*
Y653539D01*
X745762Y654170D01*
X746140Y654549D01*
X746709Y654675D01*
X747277Y654423D01*
X747561Y653791D01*
G01X746425Y651645D02*
X744531D01*
G01X753147Y647100D02*
Y653539D01*
X753337Y654170D01*
X753715Y654549D01*
X754284Y654675D01*
X754852Y654423D01*
X755136Y653791D01*
G01X754000Y651645D02*
X752106D01*
G01X759870Y650509D02*
X762900D01*
X762616Y651393D01*
X762143Y651897D01*
X761480Y652150D01*
X760817Y652024D01*
X760249Y651645D01*
X759870Y650761D01*
X759681Y650004D01*
Y649246D01*
X759870Y648489D01*
X760344Y647731D01*
X760912Y647226D01*
X761575Y647100D01*
X762237Y647352D01*
X762900Y648110D01*
G01X767540Y647100D02*
Y652150D01*
G01Y651140D02*
X768013Y651645D01*
X768487Y652024D01*
X769150Y652150D01*
X769623Y652024D01*
X770191Y651645D01*
G01X775020Y650509D02*
X778050D01*
X777766Y651393D01*
X777293Y651897D01*
X776630Y652150D01*
X775967Y652024D01*
X775399Y651645D01*
X775020Y650761D01*
X774831Y650004D01*
Y649246D01*
X775020Y648489D01*
X775494Y647731D01*
X776062Y647226D01*
X776725Y647100D01*
X777387Y647352D01*
X778050Y648110D01*
G01X782406Y647100D02*
Y652150D01*
G01Y650887D02*
X782785Y651519D01*
X783353Y652024D01*
X784110Y652150D01*
X784773Y652024D01*
X785341Y651519D01*
X785625Y650635D01*
Y647100D01*
G01X793105Y651519D02*
X792443Y652024D01*
X791875Y652150D01*
X791117Y651897D01*
X790549Y651393D01*
X790170Y650509D01*
X790075Y649625D01*
X790170Y648741D01*
X790549Y647984D01*
X791117Y647352D01*
X791875Y647100D01*
X792537Y647352D01*
X793105Y647857D01*
G01X797745Y650509D02*
X800775D01*
X800491Y651393D01*
X800018Y651897D01*
X799355Y652150D01*
X798692Y652024D01*
X798124Y651645D01*
X797745Y650761D01*
X797556Y650004D01*
Y649246D01*
X797745Y648489D01*
X798219Y647731D01*
X798787Y647226D01*
X799450Y647100D01*
X800112Y647352D01*
X800775Y648110D01*
G01X812611Y647100D02*
Y654675D01*
G01Y650887D02*
X813085Y651645D01*
X813653Y652024D01*
X814221Y652150D01*
X815073Y651897D01*
X815641Y651393D01*
X816020Y650509D01*
Y649499D01*
X815830Y648489D01*
X815452Y647731D01*
X814789Y647226D01*
X814221Y647100D01*
X813653Y647226D01*
X813085Y647605D01*
X812611Y648236D01*
G01X820470Y650509D02*
X823500D01*
X823216Y651393D01*
X822743Y651897D01*
X822080Y652150D01*
X821417Y652024D01*
X820849Y651645D01*
X820470Y650761D01*
X820281Y650004D01*
Y649246D01*
X820470Y648489D01*
X820944Y647731D01*
X821512Y647226D01*
X822175Y647100D01*
X822837Y647352D01*
X823500Y648110D01*
G01X829465Y654675D02*
Y647100D01*
G01X828140Y652150D02*
X830791D01*
G01X834673D02*
X835810Y647100D01*
X837040Y652150D01*
X838271Y647100D01*
X839408Y652150D01*
G01X843195Y650509D02*
X846225D01*
X845941Y651393D01*
X845468Y651897D01*
X844805Y652150D01*
X844142Y652024D01*
X843574Y651645D01*
X843195Y650761D01*
X843006Y650004D01*
Y649246D01*
X843195Y648489D01*
X843669Y647731D01*
X844237Y647226D01*
X844900Y647100D01*
X845562Y647352D01*
X846225Y648110D01*
G01X850770Y650509D02*
X853800D01*
X853516Y651393D01*
X853043Y651897D01*
X852380Y652150D01*
X851717Y652024D01*
X851149Y651645D01*
X850770Y650761D01*
X850581Y650004D01*
Y649246D01*
X850770Y648489D01*
X851244Y647731D01*
X851812Y647226D01*
X852475Y647100D01*
X853137Y647352D01*
X853800Y648110D01*
G01X858156Y647100D02*
Y652150D01*
G01Y650887D02*
X858535Y651519D01*
X859103Y652024D01*
X859860Y652150D01*
X860523Y652024D01*
X861091Y651519D01*
X861375Y650635D01*
Y647100D01*
G01X874915D02*
Y654675D01*
X873779Y653160D01*
G01Y647100D02*
X876052D01*
G01X880691Y653413D02*
X881260Y654170D01*
X881922Y654549D01*
X882680Y654675D01*
X883627Y654423D01*
X884290Y653791D01*
X884479Y653034D01*
X884384Y652276D01*
X884005Y651645D01*
X882112Y650382D01*
X881260Y649499D01*
X880691Y648236D01*
X880502Y647100D01*
X884479D01*
G01X888266Y650256D02*
X888929Y651140D01*
X889497Y651645D01*
X890255Y651897D01*
X890918Y651645D01*
X891391Y651140D01*
X891770Y650382D01*
X891865Y649499D01*
X891770Y648741D01*
X891391Y647984D01*
X890823Y647352D01*
X890160Y647100D01*
X889403Y647352D01*
X888740Y648110D01*
X888361Y649246D01*
X888266Y650509D01*
X888456Y652150D01*
X888740Y653034D01*
X889213Y653917D01*
X889876Y654549D01*
X890539Y654675D01*
X891202Y654423D01*
X891675Y653791D01*
G01X894800Y647100D02*
Y652150D01*
G01Y650761D02*
X895084Y651393D01*
X895557Y651897D01*
X896220Y652150D01*
X896883Y651897D01*
X897356Y651393D01*
X897640Y650761D01*
Y647100D01*
G01Y650761D02*
X897925Y651393D01*
X898398Y651897D01*
X899061Y652150D01*
X899724Y651897D01*
X900197Y651393D01*
X900481Y650635D01*
Y647100D01*
G01X905215Y652150D02*
Y647100D01*
G01Y654170D02*
X905026Y654296D01*
Y654549D01*
X905215Y654675D01*
X905405Y654549D01*
Y654296D01*
X905215Y654170D01*
G01X912790Y647100D02*
Y654675D01*
G01X929645Y647100D02*
Y652150D01*
G01Y651266D02*
X929266Y651771D01*
X928698Y652024D01*
X928035Y652150D01*
X927372Y651897D01*
X926804Y651393D01*
X926425Y650635D01*
X926236Y649625D01*
X926425Y648615D01*
X926804Y647857D01*
X927372Y647352D01*
X928035Y647100D01*
X928698Y647226D01*
X929266Y647605D01*
X929645Y648110D01*
G01X933906Y647100D02*
Y652150D01*
G01Y650887D02*
X934285Y651519D01*
X934853Y652024D01*
X935610Y652150D01*
X936273Y652024D01*
X936841Y651519D01*
X937125Y650635D01*
Y647100D01*
G01X944795Y654675D02*
Y647100D01*
G01Y648236D02*
X944416Y647605D01*
X943848Y647226D01*
X943185Y647100D01*
X942428Y647352D01*
X941860Y647984D01*
X941481Y648741D01*
X941386Y649625D01*
X941481Y650509D01*
X941860Y651266D01*
X942428Y651897D01*
X943185Y652150D01*
X943848Y652024D01*
X944321Y651771D01*
X944795Y651266D01*
G01X958240Y647100D02*
Y654675D01*
X957104Y653160D01*
G01Y647100D02*
X959377D01*
G01X964016Y653413D02*
X964585Y654170D01*
X965247Y654549D01*
X966005Y654675D01*
X966952Y654423D01*
X967615Y653791D01*
X967804Y653034D01*
X967709Y652276D01*
X967330Y651645D01*
X965437Y650382D01*
X964585Y649499D01*
X964016Y648236D01*
X963827Y647100D01*
X967804D01*
G01X971307Y648236D02*
X971875Y647605D01*
X972538Y647226D01*
X973390Y647100D01*
X974243Y647352D01*
X974905Y647857D01*
X975379Y648741D01*
X975474Y649751D01*
X975284Y650761D01*
X974811Y651393D01*
X974148Y651897D01*
X973485Y652024D01*
X972822Y651897D01*
X971970Y651393D01*
X972254Y654675D01*
X974811D01*
G01X980965Y646848D02*
X980776Y646974D01*
Y647226D01*
X980965Y647352D01*
X981155Y647226D01*
Y646974D01*
X980965Y646848D01*
G01X988540Y647100D02*
Y654675D01*
X987404Y653160D01*
G01Y647100D02*
X989677D01*
G01X994506Y647984D02*
X995169Y647352D01*
X995926Y647100D01*
X996684Y647352D01*
X997346Y648110D01*
X997820Y649246D01*
X998009Y650382D01*
Y651771D01*
X997820Y652907D01*
X997346Y653917D01*
X996778Y654423D01*
X996115Y654675D01*
X995358Y654423D01*
X994790Y653917D01*
X994411Y653160D01*
X994222Y652150D01*
X994411Y651266D01*
X994885Y650382D01*
X995453Y649877D01*
X996115Y649751D01*
X996873Y650004D01*
X997441Y650635D01*
X998009Y651771D01*
G01X1001891Y650256D02*
X1002554Y651140D01*
X1003122Y651645D01*
X1003880Y651897D01*
X1004543Y651645D01*
X1005016Y651140D01*
X1005395Y650382D01*
X1005490Y649499D01*
X1005395Y648741D01*
X1005016Y647984D01*
X1004448Y647352D01*
X1003785Y647100D01*
X1003028Y647352D01*
X1002365Y648110D01*
X1001986Y649246D01*
X1001891Y650509D01*
X1002081Y652150D01*
X1002365Y653034D01*
X1002838Y653917D01*
X1003501Y654549D01*
X1004164Y654675D01*
X1004827Y654423D01*
X1005300Y653791D01*
G01X1011265Y647100D02*
X1011928Y647226D01*
X1012686Y647605D01*
X1013159Y648236D01*
X1013349Y649120D01*
X1013159Y650004D01*
X1012591Y650761D01*
X1011739Y651140D01*
X1010792D01*
X1010224Y651393D01*
X1009750Y652024D01*
X1009561Y652907D01*
X1009845Y653791D01*
X1010508Y654423D01*
X1011265Y654675D01*
X1012023Y654423D01*
X1012686Y653791D01*
X1012970Y652907D01*
X1012780Y652024D01*
X1012307Y651393D01*
X1011739Y651140D01*
X1010792D01*
X1009940Y650761D01*
X1009372Y650004D01*
X1009182Y649120D01*
X1009372Y648236D01*
X1009845Y647605D01*
X1010603Y647226D01*
X1011265Y647100D01*
G01X1026415Y652150D02*
Y647100D01*
G01Y654170D02*
X1026226Y654296D01*
Y654549D01*
X1026415Y654675D01*
X1026605Y654549D01*
Y654296D01*
X1026415Y654170D01*
G01X1032570Y647984D02*
X1033044Y647479D01*
X1033706Y647100D01*
X1034275D01*
X1034843Y647352D01*
X1035221Y647731D01*
X1035411Y648236D01*
X1035316Y648994D01*
X1034937Y649372D01*
X1033233Y650130D01*
X1032854Y651014D01*
X1033044Y651645D01*
X1033422Y652024D01*
X1033990Y652150D01*
X1034559Y652024D01*
X1035127Y651645D01*
G01X1049140Y647100D02*
Y654675D01*
G01X1055295Y650509D02*
X1058325D01*
X1058041Y651393D01*
X1057568Y651897D01*
X1056905Y652150D01*
X1056242Y652024D01*
X1055674Y651645D01*
X1055295Y650761D01*
X1055106Y650004D01*
Y649246D01*
X1055295Y648489D01*
X1055769Y647731D01*
X1056337Y647226D01*
X1057000Y647100D01*
X1057662Y647352D01*
X1058325Y648110D01*
G01X1062870Y647984D02*
X1063344Y647479D01*
X1064006Y647100D01*
X1064575D01*
X1065143Y647352D01*
X1065521Y647731D01*
X1065711Y648236D01*
X1065616Y648994D01*
X1065237Y649372D01*
X1063533Y650130D01*
X1063154Y651014D01*
X1063344Y651645D01*
X1063722Y652024D01*
X1064290Y652150D01*
X1064859Y652024D01*
X1065427Y651645D01*
G01X1070445Y647984D02*
X1070919Y647479D01*
X1071581Y647100D01*
X1072150D01*
X1072718Y647352D01*
X1073096Y647731D01*
X1073286Y648236D01*
X1073191Y648994D01*
X1072812Y649372D01*
X1071108Y650130D01*
X1070729Y651014D01*
X1070919Y651645D01*
X1071297Y652024D01*
X1071865Y652150D01*
X1072434Y652024D01*
X1073002Y651645D01*
G01X1087015Y654675D02*
Y647100D01*
G01X1085690Y652150D02*
X1088341D01*
G01X1092981Y647100D02*
Y654675D01*
G01Y651014D02*
X1093454Y651645D01*
X1093928Y652024D01*
X1094685Y652150D01*
X1095253Y652024D01*
X1095916Y651519D01*
X1096200Y650761D01*
Y647100D01*
G01X1103870D02*
Y652150D01*
G01Y651266D02*
X1103491Y651771D01*
X1102923Y652024D01*
X1102260Y652150D01*
X1101597Y651897D01*
X1101029Y651393D01*
X1100650Y650635D01*
X1100461Y649625D01*
X1100650Y648615D01*
X1101029Y647857D01*
X1101597Y647352D01*
X1102260Y647100D01*
X1102923Y647226D01*
X1103491Y647605D01*
X1103870Y648110D01*
G01X1108131Y647100D02*
Y652150D01*
G01Y650887D02*
X1108510Y651519D01*
X1109078Y652024D01*
X1109835Y652150D01*
X1110498Y652024D01*
X1111066Y651519D01*
X1111350Y650635D01*
Y647100D01*
G01X1124890D02*
Y654675D01*
X1123754Y653160D01*
G01Y647100D02*
X1126027D01*
G01X1137200D02*
Y652150D01*
G01Y650761D02*
X1137484Y651393D01*
X1137957Y651897D01*
X1138620Y652150D01*
X1139283Y651897D01*
X1139756Y651393D01*
X1140040Y650761D01*
Y647100D01*
G01Y650761D02*
X1140325Y651393D01*
X1140798Y651897D01*
X1141461Y652150D01*
X1142124Y651897D01*
X1142597Y651393D01*
X1142881Y650635D01*
Y647100D01*
G01X1147615Y652150D02*
Y647100D01*
G01Y654170D02*
X1147426Y654296D01*
Y654549D01*
X1147615Y654675D01*
X1147805Y654549D01*
Y654296D01*
X1147615Y654170D01*
G01X1155190Y647100D02*
Y654675D01*
G01X1162576Y645711D02*
X1162955Y647352D01*
G01X398447Y735500D02*
Y743075D01*
X400814D01*
X401571Y742696D01*
X402045Y742191D01*
X402234Y741181D01*
X402045Y740171D01*
X401477Y739540D01*
X400814Y739161D01*
X398447D01*
G01X400814D02*
X402234Y735500D01*
G01X407915D02*
X407347Y735626D01*
X406779Y736131D01*
X406400Y737015D01*
X406211Y738025D01*
X406400Y739035D01*
X406779Y739919D01*
X407347Y740424D01*
X407915Y740550D01*
X408484Y740424D01*
X409052Y739919D01*
X409430Y739035D01*
X409525Y738025D01*
X409430Y737015D01*
X409052Y736131D01*
X408484Y735626D01*
X407915Y735500D01*
G01X413881Y740550D02*
Y737015D01*
X414260Y736131D01*
X414828Y735626D01*
X415490Y735500D01*
X416153Y735626D01*
X416721Y736131D01*
X417100Y737015D01*
G01Y735500D02*
Y740550D01*
G01X421740Y733606D02*
X422403Y733101D01*
X423160Y732975D01*
X423823Y733101D01*
X424391Y733732D01*
X424770Y734616D01*
Y740550D01*
G01Y739540D02*
X424391Y740045D01*
X423823Y740424D01*
X423160Y740550D01*
X422403Y740297D01*
X421929Y739793D01*
X421550Y738909D01*
X421361Y738025D01*
X421456Y737267D01*
X421835Y736384D01*
X422403Y735752D01*
X423160Y735500D01*
X423728Y735626D01*
X424391Y736131D01*
X424770Y736636D01*
G01X429031Y735500D02*
Y743075D01*
G01Y739414D02*
X429504Y740045D01*
X429978Y740424D01*
X430735Y740550D01*
X431303Y740424D01*
X431966Y739919D01*
X432250Y739161D01*
Y735500D01*
G01X436606D02*
Y740550D01*
G01Y739287D02*
X436985Y739919D01*
X437553Y740424D01*
X438310Y740550D01*
X438973Y740424D01*
X439541Y739919D01*
X439825Y739035D01*
Y735500D01*
G01X444370Y738909D02*
X447400D01*
X447116Y739793D01*
X446643Y740297D01*
X445980Y740550D01*
X445317Y740424D01*
X444749Y740045D01*
X444370Y739161D01*
X444181Y738404D01*
Y737646D01*
X444370Y736889D01*
X444844Y736131D01*
X445412Y735626D01*
X446075Y735500D01*
X446737Y735752D01*
X447400Y736510D01*
G01X451945Y736384D02*
X452419Y735879D01*
X453081Y735500D01*
X453650D01*
X454218Y735752D01*
X454596Y736131D01*
X454786Y736636D01*
X454691Y737394D01*
X454312Y737772D01*
X452608Y738530D01*
X452229Y739414D01*
X452419Y740045D01*
X452797Y740424D01*
X453365Y740550D01*
X453934Y740424D01*
X454502Y740045D01*
G01X459520Y736384D02*
X459994Y735879D01*
X460656Y735500D01*
X461225D01*
X461793Y735752D01*
X462171Y736131D01*
X462361Y736636D01*
X462266Y737394D01*
X461887Y737772D01*
X460183Y738530D01*
X459804Y739414D01*
X459994Y740045D01*
X460372Y740424D01*
X460940Y740550D01*
X461509Y740424D01*
X462077Y740045D01*
G01X394852Y827500D02*
Y835075D01*
G01X398829D02*
Y827500D01*
G01Y831287D02*
X394852D01*
G01X404415Y827500D02*
X403847Y827626D01*
X403279Y828131D01*
X402900Y829015D01*
X402711Y830025D01*
X402900Y831035D01*
X403279Y831919D01*
X403847Y832424D01*
X404415Y832550D01*
X404984Y832424D01*
X405552Y831919D01*
X405930Y831035D01*
X406025Y830025D01*
X405930Y829015D01*
X405552Y828131D01*
X404984Y827626D01*
X404415Y827500D01*
G01X411990D02*
Y835075D01*
G01X418145Y830909D02*
X421175D01*
X420891Y831793D01*
X420418Y832297D01*
X419755Y832550D01*
X419092Y832424D01*
X418524Y832045D01*
X418145Y831161D01*
X417956Y830404D01*
Y829646D01*
X418145Y828889D01*
X418619Y828131D01*
X419187Y827626D01*
X419850Y827500D01*
X420512Y827752D01*
X421175Y828510D01*
G01X437852D02*
X438610Y827879D01*
X439462Y827500D01*
X440219D01*
X440977Y827879D01*
X441545Y828510D01*
X441829Y829394D01*
X441640Y830277D01*
X441166Y831035D01*
X440314Y831540D01*
X439178Y831793D01*
X438515Y832297D01*
X438231Y833181D01*
X438420Y834065D01*
X438894Y834696D01*
X439556Y835075D01*
X440219D01*
X440882Y834823D01*
X441450Y834191D01*
G01X447415Y832550D02*
Y827500D01*
G01Y834570D02*
X447226Y834696D01*
Y834949D01*
X447415Y835075D01*
X447605Y834949D01*
Y834696D01*
X447415Y834570D01*
G01X453570Y832550D02*
X456411D01*
X453570Y827500D01*
X456411D01*
G01X461145Y830909D02*
X464175D01*
X463891Y831793D01*
X463418Y832297D01*
X462755Y832550D01*
X462092Y832424D01*
X461524Y832045D01*
X461145Y831161D01*
X460956Y830404D01*
Y829646D01*
X461145Y828889D01*
X461619Y828131D01*
X462187Y827626D01*
X462850Y827500D01*
X463512Y827752D01*
X464175Y828510D01*
G01X417473Y884500D02*
X419840Y892075D01*
X422208Y884500D01*
G01X421355Y887151D02*
X418325D01*
G01X427415Y884500D02*
Y892075D01*
G01X434990Y889550D02*
Y884500D01*
G01Y891570D02*
X434801Y891696D01*
Y891949D01*
X434990Y892075D01*
X435180Y891949D01*
Y891696D01*
X434990Y891570D01*
G01X441240Y882606D02*
X441903Y882101D01*
X442660Y881975D01*
X443323Y882101D01*
X443891Y882732D01*
X444270Y883616D01*
Y889550D01*
G01Y888540D02*
X443891Y889045D01*
X443323Y889424D01*
X442660Y889550D01*
X441903Y889297D01*
X441429Y888793D01*
X441050Y887909D01*
X440861Y887025D01*
X440956Y886267D01*
X441335Y885384D01*
X441903Y884752D01*
X442660Y884500D01*
X443228Y884626D01*
X443891Y885131D01*
X444270Y885636D01*
G01X448531Y884500D02*
Y889550D01*
G01Y888287D02*
X448910Y888919D01*
X449478Y889424D01*
X450235Y889550D01*
X450898Y889424D01*
X451466Y888919D01*
X451750Y888035D01*
Y884500D01*
G01X454875D02*
Y889550D01*
G01Y888161D02*
X455159Y888793D01*
X455632Y889297D01*
X456295Y889550D01*
X456958Y889297D01*
X457431Y888793D01*
X457715Y888161D01*
Y884500D01*
G01Y888161D02*
X458000Y888793D01*
X458473Y889297D01*
X459136Y889550D01*
X459799Y889297D01*
X460272Y888793D01*
X460556Y888035D01*
Y884500D01*
G01X463870Y887909D02*
X466900D01*
X466616Y888793D01*
X466143Y889297D01*
X465480Y889550D01*
X464817Y889424D01*
X464249Y889045D01*
X463870Y888161D01*
X463681Y887404D01*
Y886646D01*
X463870Y885889D01*
X464344Y885131D01*
X464912Y884626D01*
X465575Y884500D01*
X466237Y884752D01*
X466900Y885510D01*
G01X471256Y884500D02*
Y889550D01*
G01Y888287D02*
X471635Y888919D01*
X472203Y889424D01*
X472960Y889550D01*
X473623Y889424D01*
X474191Y888919D01*
X474475Y888035D01*
Y884500D01*
G01X480440Y892075D02*
Y884500D01*
G01X479115Y889550D02*
X481766D01*
G01X500352Y736000D02*
Y743575D01*
G01X504329D02*
Y736000D01*
G01Y739787D02*
X500352D01*
G01X509915Y736000D02*
X509347Y736126D01*
X508779Y736631D01*
X508400Y737515D01*
X508211Y738525D01*
X508400Y739535D01*
X508779Y740419D01*
X509347Y740924D01*
X509915Y741050D01*
X510484Y740924D01*
X511052Y740419D01*
X511430Y739535D01*
X511525Y738525D01*
X511430Y737515D01*
X511052Y736631D01*
X510484Y736126D01*
X509915Y736000D01*
G01X517490D02*
Y743575D01*
G01X523645Y739409D02*
X526675D01*
X526391Y740293D01*
X525918Y740797D01*
X525255Y741050D01*
X524592Y740924D01*
X524024Y740545D01*
X523645Y739661D01*
X523456Y738904D01*
Y738146D01*
X523645Y737389D01*
X524119Y736631D01*
X524687Y736126D01*
X525350Y736000D01*
X526012Y736252D01*
X526675Y737010D01*
G01X537375Y743575D02*
X538700Y736000D01*
X540215Y743575D01*
X541730Y736000D01*
X543056Y743575D01*
G01X549495Y736000D02*
Y741050D01*
G01Y740166D02*
X549116Y740671D01*
X548548Y740924D01*
X547885Y741050D01*
X547222Y740797D01*
X546654Y740293D01*
X546275Y739535D01*
X546086Y738525D01*
X546275Y737515D01*
X546654Y736757D01*
X547222Y736252D01*
X547885Y736000D01*
X548548Y736126D01*
X549116Y736505D01*
X549495Y737010D01*
G01X555365Y736000D02*
Y743575D01*
G01X562940Y736000D02*
Y743575D01*
G01X576197Y736000D02*
Y743575D01*
X578564D01*
X579321Y743196D01*
X579795Y742691D01*
X579984Y741681D01*
X579795Y740671D01*
X579227Y740040D01*
X578564Y739661D01*
X576197D01*
G01X578564D02*
X579984Y736000D01*
G01X585665D02*
X585097Y736126D01*
X584529Y736631D01*
X584150Y737515D01*
X583961Y738525D01*
X584150Y739535D01*
X584529Y740419D01*
X585097Y740924D01*
X585665Y741050D01*
X586234Y740924D01*
X586802Y740419D01*
X587180Y739535D01*
X587275Y738525D01*
X587180Y737515D01*
X586802Y736631D01*
X586234Y736126D01*
X585665Y736000D01*
G01X591631Y741050D02*
Y737515D01*
X592010Y736631D01*
X592578Y736126D01*
X593240Y736000D01*
X593903Y736126D01*
X594471Y736631D01*
X594850Y737515D01*
G01Y736000D02*
Y741050D01*
G01X599490Y734106D02*
X600153Y733601D01*
X600910Y733475D01*
X601573Y733601D01*
X602141Y734232D01*
X602520Y735116D01*
Y741050D01*
G01Y740040D02*
X602141Y740545D01*
X601573Y740924D01*
X600910Y741050D01*
X600153Y740797D01*
X599679Y740293D01*
X599300Y739409D01*
X599111Y738525D01*
X599206Y737767D01*
X599585Y736884D01*
X600153Y736252D01*
X600910Y736000D01*
X601478Y736126D01*
X602141Y736631D01*
X602520Y737136D01*
G01X606781Y736000D02*
Y743575D01*
G01Y739914D02*
X607254Y740545D01*
X607728Y740924D01*
X608485Y741050D01*
X609053Y740924D01*
X609716Y740419D01*
X610000Y739661D01*
Y736000D01*
G01X614356D02*
Y741050D01*
G01Y739787D02*
X614735Y740419D01*
X615303Y740924D01*
X616060Y741050D01*
X616723Y740924D01*
X617291Y740419D01*
X617575Y739535D01*
Y736000D01*
G01X622120Y739409D02*
X625150D01*
X624866Y740293D01*
X624393Y740797D01*
X623730Y741050D01*
X623067Y740924D01*
X622499Y740545D01*
X622120Y739661D01*
X621931Y738904D01*
Y738146D01*
X622120Y737389D01*
X622594Y736631D01*
X623162Y736126D01*
X623825Y736000D01*
X624487Y736252D01*
X625150Y737010D01*
G01X629695Y736884D02*
X630169Y736379D01*
X630831Y736000D01*
X631400D01*
X631968Y736252D01*
X632346Y736631D01*
X632536Y737136D01*
X632441Y737894D01*
X632062Y738272D01*
X630358Y739030D01*
X629979Y739914D01*
X630169Y740545D01*
X630547Y740924D01*
X631115Y741050D01*
X631684Y740924D01*
X632252Y740545D01*
G01X637270Y736884D02*
X637744Y736379D01*
X638406Y736000D01*
X638975D01*
X639543Y736252D01*
X639921Y736631D01*
X640111Y737136D01*
X640016Y737894D01*
X639637Y738272D01*
X637933Y739030D01*
X637554Y739914D01*
X637744Y740545D01*
X638122Y740924D01*
X638690Y741050D01*
X639259Y740924D01*
X639827Y740545D01*
G01X501340Y748000D02*
X500583Y748126D01*
X499920Y748631D01*
X499352Y749389D01*
X498973Y750272D01*
X498784Y751282D01*
Y752293D01*
X498973Y753303D01*
X499352Y754186D01*
X499920Y754944D01*
X500583Y755449D01*
X501340Y755575D01*
X502098Y755449D01*
X502761Y754944D01*
X503329Y754186D01*
X503708Y753303D01*
X503897Y752293D01*
Y751282D01*
X503708Y750272D01*
X503329Y749389D01*
X502761Y748631D01*
X502098Y748126D01*
X501340Y748000D01*
G01X508915Y755575D02*
Y748000D01*
G01X507590Y753050D02*
X510241D01*
G01X514881Y748000D02*
Y755575D01*
G01Y751914D02*
X515354Y752545D01*
X515828Y752924D01*
X516585Y753050D01*
X517153Y752924D01*
X517816Y752419D01*
X518100Y751661D01*
Y748000D01*
G01X522645Y751409D02*
X525675D01*
X525391Y752293D01*
X524918Y752797D01*
X524255Y753050D01*
X523592Y752924D01*
X523024Y752545D01*
X522645Y751661D01*
X522456Y750904D01*
Y750146D01*
X522645Y749389D01*
X523119Y748631D01*
X523687Y748126D01*
X524350Y748000D01*
X525012Y748252D01*
X525675Y749010D01*
G01X530315Y748000D02*
Y753050D01*
G01Y752040D02*
X530788Y752545D01*
X531262Y752924D01*
X531925Y753050D01*
X532398Y752924D01*
X532966Y752545D01*
G01X537795Y748884D02*
X538269Y748379D01*
X538931Y748000D01*
X539500D01*
X540068Y748252D01*
X540446Y748631D01*
X540636Y749136D01*
X540541Y749894D01*
X540162Y750272D01*
X538458Y751030D01*
X538079Y751914D01*
X538269Y752545D01*
X538647Y752924D01*
X539215Y753050D01*
X539784Y752924D01*
X540352Y752545D01*
G01X553892Y745475D02*
X552945Y746738D01*
X552472Y748000D01*
Y753050D01*
X552945Y754313D01*
X553892Y755575D01*
G01X561940Y748000D02*
Y755575D01*
G01X569515Y753050D02*
Y748000D01*
G01Y755070D02*
X569326Y755196D01*
Y755449D01*
X569515Y755575D01*
X569705Y755449D01*
Y755196D01*
X569515Y755070D01*
G01X575481Y748000D02*
Y755575D01*
G01X578511Y753050D02*
X575481Y750146D01*
G01X576712Y751282D02*
X578700Y748000D01*
G01X583245Y751409D02*
X586275D01*
X585991Y752293D01*
X585518Y752797D01*
X584855Y753050D01*
X584192Y752924D01*
X583624Y752545D01*
X583245Y751661D01*
X583056Y750904D01*
Y750146D01*
X583245Y749389D01*
X583719Y748631D01*
X584287Y748126D01*
X584950Y748000D01*
X585612Y748252D01*
X586275Y749010D01*
G01X598395Y751409D02*
X601425D01*
X601141Y752293D01*
X600668Y752797D01*
X600005Y753050D01*
X599342Y752924D01*
X598774Y752545D01*
X598395Y751661D01*
X598206Y750904D01*
Y750146D01*
X598395Y749389D01*
X598869Y748631D01*
X599437Y748126D01*
X600100Y748000D01*
X600762Y748252D01*
X601425Y749010D01*
G01X607390Y748000D02*
Y755575D01*
G01X614965Y748000D02*
Y755575D01*
G01X622540Y753050D02*
Y748000D01*
G01Y755070D02*
X622351Y755196D01*
Y755449D01*
X622540Y755575D01*
X622730Y755449D01*
Y755196D01*
X622540Y755070D01*
G01X628411Y745475D02*
Y753050D01*
G01Y751914D02*
X628885Y752545D01*
X629358Y752924D01*
X630115Y753050D01*
X630778Y752924D01*
X631441Y752293D01*
X631725Y751409D01*
X631820Y750525D01*
X631725Y749641D01*
X631441Y748757D01*
X630873Y748252D01*
X630115Y748000D01*
X629453Y748126D01*
X628790Y748505D01*
X628411Y749010D01*
G01X636270Y748884D02*
X636744Y748379D01*
X637406Y748000D01*
X637975D01*
X638543Y748252D01*
X638921Y748631D01*
X639111Y749136D01*
X639016Y749894D01*
X638637Y750272D01*
X636933Y751030D01*
X636554Y751914D01*
X636744Y752545D01*
X637122Y752924D01*
X637690Y753050D01*
X638259Y752924D01*
X638827Y752545D01*
G01X643845Y751409D02*
X646875D01*
X646591Y752293D01*
X646118Y752797D01*
X645455Y753050D01*
X644792Y752924D01*
X644224Y752545D01*
X643845Y751661D01*
X643656Y750904D01*
Y750146D01*
X643845Y749389D01*
X644319Y748631D01*
X644887Y748126D01*
X645550Y748000D01*
X646212Y748252D01*
X646875Y749010D01*
G01X662120Y748000D02*
Y753050D01*
G01Y752166D02*
X661741Y752671D01*
X661173Y752924D01*
X660510Y753050D01*
X659847Y752797D01*
X659279Y752293D01*
X658900Y751535D01*
X658711Y750525D01*
X658900Y749515D01*
X659279Y748757D01*
X659847Y748252D01*
X660510Y748000D01*
X661173Y748126D01*
X661741Y748505D01*
X662120Y749010D01*
G01X666381Y748000D02*
Y753050D01*
G01Y751787D02*
X666760Y752419D01*
X667328Y752924D01*
X668085Y753050D01*
X668748Y752924D01*
X669316Y752419D01*
X669600Y751535D01*
Y748000D01*
G01X677270Y755575D02*
Y748000D01*
G01Y749136D02*
X676891Y748505D01*
X676323Y748126D01*
X675660Y748000D01*
X674903Y748252D01*
X674335Y748884D01*
X673956Y749641D01*
X673861Y750525D01*
X673956Y751409D01*
X674335Y752166D01*
X674903Y752797D01*
X675660Y753050D01*
X676323Y752924D01*
X676796Y752671D01*
X677270Y752166D01*
G01X690715Y748000D02*
X690147Y748126D01*
X689579Y748631D01*
X689200Y749515D01*
X689011Y750525D01*
X689200Y751535D01*
X689579Y752419D01*
X690147Y752924D01*
X690715Y753050D01*
X691284Y752924D01*
X691852Y752419D01*
X692230Y751535D01*
X692325Y750525D01*
X692230Y749515D01*
X691852Y748631D01*
X691284Y748126D01*
X690715Y748000D01*
G01X698290Y755575D02*
Y748000D01*
G01X696965Y753050D02*
X699616D01*
G01X704256Y748000D02*
Y755575D01*
G01Y751914D02*
X704729Y752545D01*
X705203Y752924D01*
X705960Y753050D01*
X706528Y752924D01*
X707191Y752419D01*
X707475Y751661D01*
Y748000D01*
G01X712020Y751409D02*
X715050D01*
X714766Y752293D01*
X714293Y752797D01*
X713630Y753050D01*
X712967Y752924D01*
X712399Y752545D01*
X712020Y751661D01*
X711831Y750904D01*
Y750146D01*
X712020Y749389D01*
X712494Y748631D01*
X713062Y748126D01*
X713725Y748000D01*
X714387Y748252D01*
X715050Y749010D01*
G01X719690Y748000D02*
Y753050D01*
G01Y752040D02*
X720163Y752545D01*
X720637Y752924D01*
X721300Y753050D01*
X721773Y752924D01*
X722341Y752545D01*
G01X727170Y748884D02*
X727644Y748379D01*
X728306Y748000D01*
X728875D01*
X729443Y748252D01*
X729821Y748631D01*
X730011Y749136D01*
X729916Y749894D01*
X729537Y750272D01*
X727833Y751030D01*
X727454Y751914D01*
X727644Y752545D01*
X728022Y752924D01*
X728590Y753050D01*
X729159Y752924D01*
X729727Y752545D01*
G01X736639Y745475D02*
X737586Y746738D01*
X738059Y748000D01*
Y753050D01*
X737586Y754313D01*
X736639Y755575D01*
G01X499447Y759500D02*
Y767075D01*
X501719D01*
X502477Y766696D01*
X503045Y765813D01*
X503234Y764803D01*
X503045Y763793D01*
X502571Y763035D01*
X501719Y762656D01*
X499447D01*
G01X508915Y767075D02*
Y759500D01*
G01X506738Y767075D02*
X511093D01*
G01X514502Y759500D02*
Y767075D01*
G01X518479D02*
Y759500D01*
G01Y763287D02*
X514502D01*
G01X522361Y759248D02*
X525770Y767075D01*
G01X529463Y759500D02*
Y767075D01*
X533818Y759500D01*
Y767075D01*
G01X537322Y759500D02*
Y767075D01*
X539594D01*
X540352Y766696D01*
X540920Y765813D01*
X541109Y764803D01*
X540920Y763793D01*
X540446Y763035D01*
X539594Y762656D01*
X537322D01*
G01X546790Y767075D02*
Y759500D01*
G01X544613Y767075D02*
X548968D01*
G01X552377Y759500D02*
Y767075D01*
G01X556354D02*
Y759500D01*
G01Y763287D02*
X552377D01*
G01X567622Y759500D02*
X571409Y762025D01*
X567622Y764550D01*
G01X575860Y760889D02*
X578321D01*
G01Y763161D02*
X575860D01*
G01X582582Y760636D02*
X583150Y760005D01*
X583813Y759626D01*
X584665Y759500D01*
X585518Y759752D01*
X586180Y760257D01*
X586654Y761141D01*
X586749Y762151D01*
X586559Y763161D01*
X586086Y763793D01*
X585423Y764297D01*
X584760Y764424D01*
X584097Y764297D01*
X583245Y763793D01*
X583529Y767075D01*
X586086D01*
G01X596975Y759500D02*
Y764550D01*
G01Y763161D02*
X597259Y763793D01*
X597732Y764297D01*
X598395Y764550D01*
X599058Y764297D01*
X599531Y763793D01*
X599815Y763161D01*
Y759500D01*
G01Y763161D02*
X600100Y763793D01*
X600573Y764297D01*
X601236Y764550D01*
X601899Y764297D01*
X602372Y763793D01*
X602656Y763035D01*
Y759500D01*
G01X604550D02*
Y764550D01*
G01Y763161D02*
X604834Y763793D01*
X605307Y764297D01*
X605970Y764550D01*
X606633Y764297D01*
X607106Y763793D01*
X607390Y763161D01*
Y759500D01*
G01Y763161D02*
X607675Y763793D01*
X608148Y764297D01*
X608811Y764550D01*
X609474Y764297D01*
X609947Y763793D01*
X610231Y763035D01*
Y759500D01*
G01X499663Y784500D02*
Y792075D01*
X504018Y784500D01*
Y792075D01*
G01X507522Y784500D02*
Y792075D01*
X509794D01*
X510552Y791696D01*
X511120Y790813D01*
X511309Y789803D01*
X511120Y788793D01*
X510646Y788035D01*
X509794Y787656D01*
X507522D01*
G01X516990Y792075D02*
Y784500D01*
G01X514813Y792075D02*
X519168D01*
G01X522577Y784500D02*
Y792075D01*
G01X526554D02*
Y784500D01*
G01Y788287D02*
X522577D01*
G01X537727Y785510D02*
X538485Y784879D01*
X539337Y784500D01*
X540094D01*
X540852Y784879D01*
X541420Y785510D01*
X541704Y786394D01*
X541515Y787277D01*
X541041Y788035D01*
X540189Y788540D01*
X539053Y788793D01*
X538390Y789297D01*
X538106Y790181D01*
X538295Y791065D01*
X538769Y791696D01*
X539431Y792075D01*
X540094D01*
X540757Y791823D01*
X541325Y791191D01*
G01X547290Y789550D02*
Y784500D01*
G01Y791570D02*
X547101Y791696D01*
Y791949D01*
X547290Y792075D01*
X547480Y791949D01*
Y791696D01*
X547290Y791570D01*
G01X553445Y789550D02*
X556286D01*
X553445Y784500D01*
X556286D01*
G01X561020Y787909D02*
X564050D01*
X563766Y788793D01*
X563293Y789297D01*
X562630Y789550D01*
X561967Y789424D01*
X561399Y789045D01*
X561020Y788161D01*
X560831Y787404D01*
Y786646D01*
X561020Y785889D01*
X561494Y785131D01*
X562062Y784626D01*
X562725Y784500D01*
X563387Y784752D01*
X564050Y785510D01*
G01X575507Y786015D02*
X576075Y785131D01*
X576833Y784626D01*
X577685Y784500D01*
X578443Y784626D01*
X579200Y785257D01*
X579674Y786015D01*
X579768Y786772D01*
X579579Y787656D01*
X578916Y788287D01*
X578253Y788540D01*
X577401D01*
G01X578253D02*
X578821Y788919D01*
X579295Y789550D01*
X579484Y790307D01*
X579295Y791065D01*
X578821Y791696D01*
X577969Y792075D01*
X577117Y791949D01*
X576265Y791444D01*
G01X585165Y784248D02*
X584976Y784374D01*
Y784626D01*
X585165Y784752D01*
X585355Y784626D01*
Y784374D01*
X585165Y784248D01*
G01X590657Y785636D02*
X591225Y785005D01*
X591888Y784626D01*
X592740Y784500D01*
X593593Y784752D01*
X594255Y785257D01*
X594729Y786141D01*
X594824Y787151D01*
X594634Y788161D01*
X594161Y788793D01*
X593498Y789297D01*
X592835Y789424D01*
X592172Y789297D01*
X591320Y788793D01*
X591604Y792075D01*
X594161D01*
G01X598232Y785636D02*
X598800Y785005D01*
X599463Y784626D01*
X600315Y784500D01*
X601168Y784752D01*
X601830Y785257D01*
X602304Y786141D01*
X602399Y787151D01*
X602209Y788161D01*
X601736Y788793D01*
X601073Y789297D01*
X600410Y789424D01*
X599747Y789297D01*
X598895Y788793D01*
X599179Y792075D01*
X601736D01*
G01X605050Y784500D02*
Y789550D01*
G01Y788161D02*
X605334Y788793D01*
X605807Y789297D01*
X606470Y789550D01*
X607133Y789297D01*
X607606Y788793D01*
X607890Y788161D01*
Y784500D01*
G01Y788161D02*
X608175Y788793D01*
X608648Y789297D01*
X609311Y789550D01*
X609974Y789297D01*
X610447Y788793D01*
X610731Y788035D01*
Y784500D01*
G01X612625D02*
Y789550D01*
G01Y788161D02*
X612909Y788793D01*
X613382Y789297D01*
X614045Y789550D01*
X614708Y789297D01*
X615181Y788793D01*
X615465Y788161D01*
Y784500D01*
G01Y788161D02*
X615750Y788793D01*
X616223Y789297D01*
X616886Y789550D01*
X617549Y789297D01*
X618022Y788793D01*
X618306Y788035D01*
Y784500D01*
G01X630142Y781975D02*
X629195Y783238D01*
X628722Y784500D01*
Y789550D01*
X629195Y790813D01*
X630142Y792075D01*
G01X638190Y784500D02*
X637622Y784626D01*
X637054Y785131D01*
X636675Y786015D01*
X636486Y787025D01*
X636675Y788035D01*
X637054Y788919D01*
X637622Y789424D01*
X638190Y789550D01*
X638759Y789424D01*
X639327Y788919D01*
X639705Y788035D01*
X639800Y787025D01*
X639705Y786015D01*
X639327Y785131D01*
X638759Y784626D01*
X638190Y784500D01*
G01X644156D02*
Y789550D01*
G01Y788287D02*
X644535Y788919D01*
X645103Y789424D01*
X645860Y789550D01*
X646523Y789424D01*
X647091Y788919D01*
X647375Y788035D01*
Y784500D01*
G01X659211D02*
Y792075D01*
G01Y788287D02*
X659685Y789045D01*
X660253Y789424D01*
X660821Y789550D01*
X661673Y789297D01*
X662241Y788793D01*
X662620Y787909D01*
Y786899D01*
X662430Y785889D01*
X662052Y785131D01*
X661389Y784626D01*
X660821Y784500D01*
X660253Y784626D01*
X659685Y785005D01*
X659211Y785636D01*
G01X667165Y784500D02*
Y789550D01*
G01Y788540D02*
X667638Y789045D01*
X668112Y789424D01*
X668775Y789550D01*
X669248Y789424D01*
X669816Y789045D01*
G01X674645Y787909D02*
X677675D01*
X677391Y788793D01*
X676918Y789297D01*
X676255Y789550D01*
X675592Y789424D01*
X675024Y789045D01*
X674645Y788161D01*
X674456Y787404D01*
Y786646D01*
X674645Y785889D01*
X675119Y785131D01*
X675687Y784626D01*
X676350Y784500D01*
X677012Y784752D01*
X677675Y785510D01*
G01X685345Y784500D02*
Y789550D01*
G01Y788666D02*
X684966Y789171D01*
X684398Y789424D01*
X683735Y789550D01*
X683072Y789297D01*
X682504Y788793D01*
X682125Y788035D01*
X681936Y787025D01*
X682125Y786015D01*
X682504Y785257D01*
X683072Y784752D01*
X683735Y784500D01*
X684398Y784626D01*
X684966Y785005D01*
X685345Y785510D01*
G01X689606Y784500D02*
Y792075D01*
G01X692636Y789550D02*
X689606Y786646D01*
G01X690837Y787782D02*
X692825Y784500D01*
G01X700495D02*
Y789550D01*
G01Y788666D02*
X700116Y789171D01*
X699548Y789424D01*
X698885Y789550D01*
X698222Y789297D01*
X697654Y788793D01*
X697275Y788035D01*
X697086Y787025D01*
X697275Y786015D01*
X697654Y785257D01*
X698222Y784752D01*
X698885Y784500D01*
X699548Y784626D01*
X700116Y785005D01*
X700495Y785510D01*
G01X703998Y789550D02*
X705135Y784500D01*
X706365Y789550D01*
X707596Y784500D01*
X708733Y789550D01*
G01X715645Y784500D02*
Y789550D01*
G01Y788666D02*
X715266Y789171D01*
X714698Y789424D01*
X714035Y789550D01*
X713372Y789297D01*
X712804Y788793D01*
X712425Y788035D01*
X712236Y787025D01*
X712425Y786015D01*
X712804Y785257D01*
X713372Y784752D01*
X714035Y784500D01*
X714698Y784626D01*
X715266Y785005D01*
X715645Y785510D01*
G01X719527Y782228D02*
X720095Y781975D01*
X720853Y782228D01*
X721326Y782732D01*
X721705Y783364D01*
X722273Y785384D01*
X723504Y789550D01*
G01X720474D02*
X722273Y785384D01*
G01X729564Y781975D02*
X730511Y783238D01*
X730984Y784500D01*
Y789550D01*
X730511Y790813D01*
X729564Y792075D01*
G01X499663Y772500D02*
Y780075D01*
X504018Y772500D01*
Y780075D01*
G01X507522Y772500D02*
Y780075D01*
X509794D01*
X510552Y779696D01*
X511120Y778813D01*
X511309Y777803D01*
X511120Y776793D01*
X510646Y776035D01*
X509794Y775656D01*
X507522D01*
G01X516990Y780075D02*
Y772500D01*
G01X514813Y780075D02*
X519168D01*
G01X522577Y772500D02*
Y780075D01*
G01X526554D02*
Y772500D01*
G01Y776287D02*
X522577D01*
G01X537727Y773510D02*
X538485Y772879D01*
X539337Y772500D01*
X540094D01*
X540852Y772879D01*
X541420Y773510D01*
X541704Y774394D01*
X541515Y775277D01*
X541041Y776035D01*
X540189Y776540D01*
X539053Y776793D01*
X538390Y777297D01*
X538106Y778181D01*
X538295Y779065D01*
X538769Y779696D01*
X539431Y780075D01*
X540094D01*
X540757Y779823D01*
X541325Y779191D01*
G01X547290Y777550D02*
Y772500D01*
G01Y779570D02*
X547101Y779696D01*
Y779949D01*
X547290Y780075D01*
X547480Y779949D01*
Y779696D01*
X547290Y779570D01*
G01X553445Y777550D02*
X556286D01*
X553445Y772500D01*
X556286D01*
G01X561020Y775909D02*
X564050D01*
X563766Y776793D01*
X563293Y777297D01*
X562630Y777550D01*
X561967Y777424D01*
X561399Y777045D01*
X561020Y776161D01*
X560831Y775404D01*
Y774646D01*
X561020Y773889D01*
X561494Y773131D01*
X562062Y772626D01*
X562725Y772500D01*
X563387Y772752D01*
X564050Y773510D01*
G01X575791Y778813D02*
X576360Y779570D01*
X577022Y779949D01*
X577780Y780075D01*
X578727Y779823D01*
X579390Y779191D01*
X579579Y778434D01*
X579484Y777676D01*
X579105Y777045D01*
X577212Y775782D01*
X576360Y774899D01*
X575791Y773636D01*
X575602Y772500D01*
X579579D01*
G01X585165Y772248D02*
X584976Y772374D01*
Y772626D01*
X585165Y772752D01*
X585355Y772626D01*
Y772374D01*
X585165Y772248D01*
G01X592740Y772500D02*
Y780075D01*
X591604Y778560D01*
G01Y772500D02*
X593877D01*
G01X600315D02*
X600978Y772626D01*
X601736Y773005D01*
X602209Y773636D01*
X602399Y774520D01*
X602209Y775404D01*
X601641Y776161D01*
X600789Y776540D01*
X599842D01*
X599274Y776793D01*
X598800Y777424D01*
X598611Y778307D01*
X598895Y779191D01*
X599558Y779823D01*
X600315Y780075D01*
X601073Y779823D01*
X601736Y779191D01*
X602020Y778307D01*
X601830Y777424D01*
X601357Y776793D01*
X600789Y776540D01*
X599842D01*
X598990Y776161D01*
X598422Y775404D01*
X598232Y774520D01*
X598422Y773636D01*
X598895Y773005D01*
X599653Y772626D01*
X600315Y772500D01*
G01X605050D02*
Y777550D01*
G01Y776161D02*
X605334Y776793D01*
X605807Y777297D01*
X606470Y777550D01*
X607133Y777297D01*
X607606Y776793D01*
X607890Y776161D01*
Y772500D01*
G01Y776161D02*
X608175Y776793D01*
X608648Y777297D01*
X609311Y777550D01*
X609974Y777297D01*
X610447Y776793D01*
X610731Y776035D01*
Y772500D01*
G01X612625D02*
Y777550D01*
G01Y776161D02*
X612909Y776793D01*
X613382Y777297D01*
X614045Y777550D01*
X614708Y777297D01*
X615181Y776793D01*
X615465Y776161D01*
Y772500D01*
G01Y776161D02*
X615750Y776793D01*
X616223Y777297D01*
X616886Y777550D01*
X617549Y777297D01*
X618022Y776793D01*
X618306Y776035D01*
Y772500D01*
G01X630142Y769975D02*
X629195Y771238D01*
X628722Y772500D01*
Y777550D01*
X629195Y778813D01*
X630142Y780075D01*
G01X638190Y772500D02*
X637622Y772626D01*
X637054Y773131D01*
X636675Y774015D01*
X636486Y775025D01*
X636675Y776035D01*
X637054Y776919D01*
X637622Y777424D01*
X638190Y777550D01*
X638759Y777424D01*
X639327Y776919D01*
X639705Y776035D01*
X639800Y775025D01*
X639705Y774015D01*
X639327Y773131D01*
X638759Y772626D01*
X638190Y772500D01*
G01X644156D02*
Y777550D01*
G01Y776287D02*
X644535Y776919D01*
X645103Y777424D01*
X645860Y777550D01*
X646523Y777424D01*
X647091Y776919D01*
X647375Y776035D01*
Y772500D01*
G01X659211D02*
Y780075D01*
G01Y776287D02*
X659685Y777045D01*
X660253Y777424D01*
X660821Y777550D01*
X661673Y777297D01*
X662241Y776793D01*
X662620Y775909D01*
Y774899D01*
X662430Y773889D01*
X662052Y773131D01*
X661389Y772626D01*
X660821Y772500D01*
X660253Y772626D01*
X659685Y773005D01*
X659211Y773636D01*
G01X667165Y772500D02*
Y777550D01*
G01Y776540D02*
X667638Y777045D01*
X668112Y777424D01*
X668775Y777550D01*
X669248Y777424D01*
X669816Y777045D01*
G01X674645Y775909D02*
X677675D01*
X677391Y776793D01*
X676918Y777297D01*
X676255Y777550D01*
X675592Y777424D01*
X675024Y777045D01*
X674645Y776161D01*
X674456Y775404D01*
Y774646D01*
X674645Y773889D01*
X675119Y773131D01*
X675687Y772626D01*
X676350Y772500D01*
X677012Y772752D01*
X677675Y773510D01*
G01X685345Y772500D02*
Y777550D01*
G01Y776666D02*
X684966Y777171D01*
X684398Y777424D01*
X683735Y777550D01*
X683072Y777297D01*
X682504Y776793D01*
X682125Y776035D01*
X681936Y775025D01*
X682125Y774015D01*
X682504Y773257D01*
X683072Y772752D01*
X683735Y772500D01*
X684398Y772626D01*
X684966Y773005D01*
X685345Y773510D01*
G01X689606Y772500D02*
Y780075D01*
G01X692636Y777550D02*
X689606Y774646D01*
G01X690837Y775782D02*
X692825Y772500D01*
G01X700495D02*
Y777550D01*
G01Y776666D02*
X700116Y777171D01*
X699548Y777424D01*
X698885Y777550D01*
X698222Y777297D01*
X697654Y776793D01*
X697275Y776035D01*
X697086Y775025D01*
X697275Y774015D01*
X697654Y773257D01*
X698222Y772752D01*
X698885Y772500D01*
X699548Y772626D01*
X700116Y773005D01*
X700495Y773510D01*
G01X703998Y777550D02*
X705135Y772500D01*
X706365Y777550D01*
X707596Y772500D01*
X708733Y777550D01*
G01X715645Y772500D02*
Y777550D01*
G01Y776666D02*
X715266Y777171D01*
X714698Y777424D01*
X714035Y777550D01*
X713372Y777297D01*
X712804Y776793D01*
X712425Y776035D01*
X712236Y775025D01*
X712425Y774015D01*
X712804Y773257D01*
X713372Y772752D01*
X714035Y772500D01*
X714698Y772626D01*
X715266Y773005D01*
X715645Y773510D01*
G01X719527Y770228D02*
X720095Y769975D01*
X720853Y770228D01*
X721326Y770732D01*
X721705Y771364D01*
X722273Y773384D01*
X723504Y777550D01*
G01X720474D02*
X722273Y773384D01*
G01X729564Y769975D02*
X730511Y771238D01*
X730984Y772500D01*
Y777550D01*
X730511Y778813D01*
X729564Y780075D01*
G01X499663Y798000D02*
Y805575D01*
X504018Y798000D01*
Y805575D01*
G01X507522Y798000D02*
Y805575D01*
X509794D01*
X510552Y805196D01*
X511120Y804313D01*
X511309Y803303D01*
X511120Y802293D01*
X510646Y801535D01*
X509794Y801156D01*
X507522D01*
G01X516990Y805575D02*
Y798000D01*
G01X514813Y805575D02*
X519168D01*
G01X522577Y798000D02*
Y805575D01*
G01X526554D02*
Y798000D01*
G01Y801787D02*
X522577D01*
G01X537727Y799010D02*
X538485Y798379D01*
X539337Y798000D01*
X540094D01*
X540852Y798379D01*
X541420Y799010D01*
X541704Y799894D01*
X541515Y800777D01*
X541041Y801535D01*
X540189Y802040D01*
X539053Y802293D01*
X538390Y802797D01*
X538106Y803681D01*
X538295Y804565D01*
X538769Y805196D01*
X539431Y805575D01*
X540094D01*
X540757Y805323D01*
X541325Y804691D01*
G01X547290Y803050D02*
Y798000D01*
G01Y805070D02*
X547101Y805196D01*
Y805449D01*
X547290Y805575D01*
X547480Y805449D01*
Y805196D01*
X547290Y805070D01*
G01X553445Y803050D02*
X556286D01*
X553445Y798000D01*
X556286D01*
G01X561020Y801409D02*
X564050D01*
X563766Y802293D01*
X563293Y802797D01*
X562630Y803050D01*
X561967Y802924D01*
X561399Y802545D01*
X561020Y801661D01*
X560831Y800904D01*
Y800146D01*
X561020Y799389D01*
X561494Y798631D01*
X562062Y798126D01*
X562725Y798000D01*
X563387Y798252D01*
X564050Y799010D01*
G01X571909Y798000D02*
X568122Y800525D01*
X571909Y803050D01*
G01X583082Y799136D02*
X583650Y798505D01*
X584313Y798126D01*
X585165Y798000D01*
X586018Y798252D01*
X586680Y798757D01*
X587154Y799641D01*
X587249Y800651D01*
X587059Y801661D01*
X586586Y802293D01*
X585923Y802797D01*
X585260Y802924D01*
X584597Y802797D01*
X583745Y802293D01*
X584029Y805575D01*
X586586D01*
G01X589900Y798000D02*
Y803050D01*
G01Y801661D02*
X590184Y802293D01*
X590657Y802797D01*
X591320Y803050D01*
X591983Y802797D01*
X592456Y802293D01*
X592740Y801661D01*
Y798000D01*
G01Y801661D02*
X593025Y802293D01*
X593498Y802797D01*
X594161Y803050D01*
X594824Y802797D01*
X595297Y802293D01*
X595581Y801535D01*
Y798000D01*
G01X597475D02*
Y803050D01*
G01Y801661D02*
X597759Y802293D01*
X598232Y802797D01*
X598895Y803050D01*
X599558Y802797D01*
X600031Y802293D01*
X600315Y801661D01*
Y798000D01*
G01Y801661D02*
X600600Y802293D01*
X601073Y802797D01*
X601736Y803050D01*
X602399Y802797D01*
X602872Y802293D01*
X603156Y801535D01*
Y798000D01*
G01X614992Y795475D02*
X614045Y796738D01*
X613572Y798000D01*
Y803050D01*
X614045Y804313D01*
X614992Y805575D01*
G01X621431Y798000D02*
Y803050D01*
G01Y801787D02*
X621810Y802419D01*
X622378Y802924D01*
X623135Y803050D01*
X623798Y802924D01*
X624366Y802419D01*
X624650Y801535D01*
Y798000D01*
G01X630615D02*
X630047Y798126D01*
X629479Y798631D01*
X629100Y799515D01*
X628911Y800525D01*
X629100Y801535D01*
X629479Y802419D01*
X630047Y802924D01*
X630615Y803050D01*
X631184Y802924D01*
X631752Y802419D01*
X632130Y801535D01*
X632225Y800525D01*
X632130Y799515D01*
X631752Y798631D01*
X631184Y798126D01*
X630615Y798000D01*
G01X638190Y805575D02*
Y798000D01*
G01X636865Y803050D02*
X639516D01*
G01X653340Y798000D02*
X652772Y798126D01*
X652204Y798631D01*
X651825Y799515D01*
X651636Y800525D01*
X651825Y801535D01*
X652204Y802419D01*
X652772Y802924D01*
X653340Y803050D01*
X653909Y802924D01*
X654477Y802419D01*
X654855Y801535D01*
X654950Y800525D01*
X654855Y799515D01*
X654477Y798631D01*
X653909Y798126D01*
X653340Y798000D01*
G01X659306D02*
Y803050D01*
G01Y801787D02*
X659685Y802419D01*
X660253Y802924D01*
X661010Y803050D01*
X661673Y802924D01*
X662241Y802419D01*
X662525Y801535D01*
Y798000D01*
G01X674361D02*
Y805575D01*
G01Y801787D02*
X674835Y802545D01*
X675403Y802924D01*
X675971Y803050D01*
X676823Y802797D01*
X677391Y802293D01*
X677770Y801409D01*
Y800399D01*
X677580Y799389D01*
X677202Y798631D01*
X676539Y798126D01*
X675971Y798000D01*
X675403Y798126D01*
X674835Y798505D01*
X674361Y799136D01*
G01X682315Y798000D02*
Y803050D01*
G01Y802040D02*
X682788Y802545D01*
X683262Y802924D01*
X683925Y803050D01*
X684398Y802924D01*
X684966Y802545D01*
G01X689795Y801409D02*
X692825D01*
X692541Y802293D01*
X692068Y802797D01*
X691405Y803050D01*
X690742Y802924D01*
X690174Y802545D01*
X689795Y801661D01*
X689606Y800904D01*
Y800146D01*
X689795Y799389D01*
X690269Y798631D01*
X690837Y798126D01*
X691500Y798000D01*
X692162Y798252D01*
X692825Y799010D01*
G01X700495Y798000D02*
Y803050D01*
G01Y802166D02*
X700116Y802671D01*
X699548Y802924D01*
X698885Y803050D01*
X698222Y802797D01*
X697654Y802293D01*
X697275Y801535D01*
X697086Y800525D01*
X697275Y799515D01*
X697654Y798757D01*
X698222Y798252D01*
X698885Y798000D01*
X699548Y798126D01*
X700116Y798505D01*
X700495Y799010D01*
G01X704756Y798000D02*
Y805575D01*
G01X707786Y803050D02*
X704756Y800146D01*
G01X705987Y801282D02*
X707975Y798000D01*
G01X715645D02*
Y803050D01*
G01Y802166D02*
X715266Y802671D01*
X714698Y802924D01*
X714035Y803050D01*
X713372Y802797D01*
X712804Y802293D01*
X712425Y801535D01*
X712236Y800525D01*
X712425Y799515D01*
X712804Y798757D01*
X713372Y798252D01*
X714035Y798000D01*
X714698Y798126D01*
X715266Y798505D01*
X715645Y799010D01*
G01X719148Y803050D02*
X720285Y798000D01*
X721515Y803050D01*
X722746Y798000D01*
X723883Y803050D01*
G01X730795Y798000D02*
Y803050D01*
G01Y802166D02*
X730416Y802671D01*
X729848Y802924D01*
X729185Y803050D01*
X728522Y802797D01*
X727954Y802293D01*
X727575Y801535D01*
X727386Y800525D01*
X727575Y799515D01*
X727954Y798757D01*
X728522Y798252D01*
X729185Y798000D01*
X729848Y798126D01*
X730416Y798505D01*
X730795Y799010D01*
G01X734677Y795728D02*
X735245Y795475D01*
X736003Y795728D01*
X736476Y796232D01*
X736855Y796864D01*
X737423Y798884D01*
X738654Y803050D01*
G01X735624D02*
X737423Y798884D01*
G01X744714Y795475D02*
X745661Y796738D01*
X746134Y798000D01*
Y803050D01*
X745661Y804313D01*
X744714Y805575D01*
G01X500367Y809475D02*
X499420Y810738D01*
X498947Y812000D01*
Y817050D01*
X499420Y818313D01*
X500367Y819575D01*
G01X506427Y813010D02*
X507185Y812379D01*
X508037Y812000D01*
X508794D01*
X509552Y812379D01*
X510120Y813010D01*
X510404Y813894D01*
X510215Y814777D01*
X509741Y815535D01*
X508889Y816040D01*
X507753Y816293D01*
X507090Y816797D01*
X506806Y817681D01*
X506995Y818565D01*
X507469Y819196D01*
X508131Y819575D01*
X508794D01*
X509457Y819323D01*
X510025Y818691D01*
G01X514381Y817050D02*
Y813515D01*
X514760Y812631D01*
X515328Y812126D01*
X515990Y812000D01*
X516653Y812126D01*
X517221Y812631D01*
X517600Y813515D01*
G01Y812000D02*
Y817050D01*
G01X522240Y812000D02*
Y817050D01*
G01Y816040D02*
X522713Y816545D01*
X523187Y816924D01*
X523850Y817050D01*
X524323Y816924D01*
X524891Y816545D01*
G01X530572Y812000D02*
Y818439D01*
X530762Y819070D01*
X531140Y819449D01*
X531709Y819575D01*
X532277Y819323D01*
X532561Y818691D01*
G01X531425Y816545D02*
X529531D01*
G01X540420Y812000D02*
Y817050D01*
G01Y816166D02*
X540041Y816671D01*
X539473Y816924D01*
X538810Y817050D01*
X538147Y816797D01*
X537579Y816293D01*
X537200Y815535D01*
X537011Y814525D01*
X537200Y813515D01*
X537579Y812757D01*
X538147Y812252D01*
X538810Y812000D01*
X539473Y812126D01*
X540041Y812505D01*
X540420Y813010D01*
G01X547805Y816419D02*
X547143Y816924D01*
X546575Y817050D01*
X545817Y816797D01*
X545249Y816293D01*
X544870Y815409D01*
X544775Y814525D01*
X544870Y813641D01*
X545249Y812884D01*
X545817Y812252D01*
X546575Y812000D01*
X547237Y812252D01*
X547805Y812757D01*
G01X552445Y815409D02*
X555475D01*
X555191Y816293D01*
X554718Y816797D01*
X554055Y817050D01*
X553392Y816924D01*
X552824Y816545D01*
X552445Y815661D01*
X552256Y814904D01*
Y814146D01*
X552445Y813389D01*
X552919Y812631D01*
X553487Y812126D01*
X554150Y812000D01*
X554812Y812252D01*
X555475Y813010D01*
G01X569015Y819575D02*
Y812000D01*
G01X567690Y817050D02*
X570341D01*
G01X575265Y812000D02*
Y817050D01*
G01Y816040D02*
X575738Y816545D01*
X576212Y816924D01*
X576875Y817050D01*
X577348Y816924D01*
X577916Y816545D01*
G01X582745Y815409D02*
X585775D01*
X585491Y816293D01*
X585018Y816797D01*
X584355Y817050D01*
X583692Y816924D01*
X583124Y816545D01*
X582745Y815661D01*
X582556Y814904D01*
Y814146D01*
X582745Y813389D01*
X583219Y812631D01*
X583787Y812126D01*
X584450Y812000D01*
X585112Y812252D01*
X585775Y813010D01*
G01X593445Y812000D02*
Y817050D01*
G01Y816166D02*
X593066Y816671D01*
X592498Y816924D01*
X591835Y817050D01*
X591172Y816797D01*
X590604Y816293D01*
X590225Y815535D01*
X590036Y814525D01*
X590225Y813515D01*
X590604Y812757D01*
X591172Y812252D01*
X591835Y812000D01*
X592498Y812126D01*
X593066Y812505D01*
X593445Y813010D01*
G01X599315Y819575D02*
Y812000D01*
G01X597990Y817050D02*
X600641D01*
G01X604050Y812000D02*
Y817050D01*
G01Y815661D02*
X604334Y816293D01*
X604807Y816797D01*
X605470Y817050D01*
X606133Y816797D01*
X606606Y816293D01*
X606890Y815661D01*
Y812000D01*
G01Y815661D02*
X607175Y816293D01*
X607648Y816797D01*
X608311Y817050D01*
X608974Y816797D01*
X609447Y816293D01*
X609731Y815535D01*
Y812000D01*
G01X613045Y815409D02*
X616075D01*
X615791Y816293D01*
X615318Y816797D01*
X614655Y817050D01*
X613992Y816924D01*
X613424Y816545D01*
X613045Y815661D01*
X612856Y814904D01*
Y814146D01*
X613045Y813389D01*
X613519Y812631D01*
X614087Y812126D01*
X614750Y812000D01*
X615412Y812252D01*
X616075Y813010D01*
G01X620431Y812000D02*
Y817050D01*
G01Y815787D02*
X620810Y816419D01*
X621378Y816924D01*
X622135Y817050D01*
X622798Y816924D01*
X623366Y816419D01*
X623650Y815535D01*
Y812000D01*
G01X629615Y819575D02*
Y812000D01*
G01X628290Y817050D02*
X630941D01*
G01X644765D02*
Y812000D01*
G01Y819070D02*
X644576Y819196D01*
Y819449D01*
X644765Y819575D01*
X644955Y819449D01*
Y819196D01*
X644765Y819070D01*
G01X650920Y812884D02*
X651394Y812379D01*
X652056Y812000D01*
X652625D01*
X653193Y812252D01*
X653571Y812631D01*
X653761Y813136D01*
X653666Y813894D01*
X653287Y814272D01*
X651583Y815030D01*
X651204Y815914D01*
X651394Y816545D01*
X651772Y816924D01*
X652340Y817050D01*
X652909Y816924D01*
X653477Y816545D01*
G01X665502Y812000D02*
Y819575D01*
G01X669479D02*
Y812000D01*
G01Y815787D02*
X665502D01*
G01X672698Y812000D02*
X675065Y819575D01*
X677433Y812000D01*
G01X676580Y814651D02*
X673550D01*
G01X680652Y813010D02*
X681410Y812379D01*
X682262Y812000D01*
X683019D01*
X683777Y812379D01*
X684345Y813010D01*
X684629Y813894D01*
X684440Y814777D01*
X683966Y815535D01*
X683114Y816040D01*
X681978Y816293D01*
X681315Y816797D01*
X681031Y817681D01*
X681220Y818565D01*
X681694Y819196D01*
X682356Y819575D01*
X683019D01*
X683682Y819323D01*
X684250Y818691D01*
G01X688322Y819575D02*
Y812000D01*
X692109D01*
G01X705365D02*
X704797Y812126D01*
X704229Y812631D01*
X703850Y813515D01*
X703661Y814525D01*
X703850Y815535D01*
X704229Y816419D01*
X704797Y816924D01*
X705365Y817050D01*
X705934Y816924D01*
X706502Y816419D01*
X706880Y815535D01*
X706975Y814525D01*
X706880Y813515D01*
X706502Y812631D01*
X705934Y812126D01*
X705365Y812000D01*
G01X711615D02*
Y817050D01*
G01Y816040D02*
X712088Y816545D01*
X712562Y816924D01*
X713225Y817050D01*
X713698Y816924D01*
X714266Y816545D01*
G01X726197Y819575D02*
Y812000D01*
X729984D01*
G01X734245Y815409D02*
X737275D01*
X736991Y816293D01*
X736518Y816797D01*
X735855Y817050D01*
X735192Y816924D01*
X734624Y816545D01*
X734245Y815661D01*
X734056Y814904D01*
Y814146D01*
X734245Y813389D01*
X734719Y812631D01*
X735287Y812126D01*
X735950Y812000D01*
X736612Y812252D01*
X737275Y813010D01*
G01X744945Y812000D02*
Y817050D01*
G01Y816166D02*
X744566Y816671D01*
X743998Y816924D01*
X743335Y817050D01*
X742672Y816797D01*
X742104Y816293D01*
X741725Y815535D01*
X741536Y814525D01*
X741725Y813515D01*
X742104Y812757D01*
X742672Y812252D01*
X743335Y812000D01*
X743998Y812126D01*
X744566Y812505D01*
X744945Y813010D01*
G01X752520Y819575D02*
Y812000D01*
G01Y813136D02*
X752141Y812505D01*
X751573Y812126D01*
X750910Y812000D01*
X750153Y812252D01*
X749585Y812884D01*
X749206Y813641D01*
X749111Y814525D01*
X749206Y815409D01*
X749585Y816166D01*
X750153Y816797D01*
X750910Y817050D01*
X751573Y816924D01*
X752046Y816671D01*
X752520Y816166D01*
G01X764166Y812000D02*
Y819575D01*
X767765D01*
G01X766439Y815914D02*
X764166D01*
G01X772215Y812000D02*
Y817050D01*
G01Y816040D02*
X772688Y816545D01*
X773162Y816924D01*
X773825Y817050D01*
X774298Y816924D01*
X774866Y816545D01*
G01X779695Y815409D02*
X782725D01*
X782441Y816293D01*
X781968Y816797D01*
X781305Y817050D01*
X780642Y816924D01*
X780074Y816545D01*
X779695Y815661D01*
X779506Y814904D01*
Y814146D01*
X779695Y813389D01*
X780169Y812631D01*
X780737Y812126D01*
X781400Y812000D01*
X782062Y812252D01*
X782725Y813010D01*
G01X787270Y815409D02*
X790300D01*
X790016Y816293D01*
X789543Y816797D01*
X788880Y817050D01*
X788217Y816924D01*
X787649Y816545D01*
X787270Y815661D01*
X787081Y814904D01*
Y814146D01*
X787270Y813389D01*
X787744Y812631D01*
X788312Y812126D01*
X788975Y812000D01*
X789637Y812252D01*
X790300Y813010D01*
G01X801852Y812000D02*
Y819575D01*
G01X805829D02*
Y812000D01*
G01Y815787D02*
X801852D01*
G01X809048Y812000D02*
X811415Y819575D01*
X813783Y812000D01*
G01X812930Y814651D02*
X809900D01*
G01X817002Y813010D02*
X817760Y812379D01*
X818612Y812000D01*
X819369D01*
X820127Y812379D01*
X820695Y813010D01*
X820979Y813894D01*
X820790Y814777D01*
X820316Y815535D01*
X819464Y816040D01*
X818328Y816293D01*
X817665Y816797D01*
X817381Y817681D01*
X817570Y818565D01*
X818044Y819196D01*
X818706Y819575D01*
X819369D01*
X820032Y819323D01*
X820600Y818691D01*
G01X824672Y819575D02*
Y812000D01*
X828459D01*
G01X834614Y809475D02*
X835561Y810738D01*
X836034Y812000D01*
Y817050D01*
X835561Y818313D01*
X834614Y819575D01*
G01X499367Y832475D02*
X498420Y833738D01*
X497947Y835000D01*
Y840050D01*
X498420Y841313D01*
X499367Y842575D01*
G01X505427Y836010D02*
X506185Y835379D01*
X507037Y835000D01*
X507794D01*
X508552Y835379D01*
X509120Y836010D01*
X509404Y836894D01*
X509215Y837777D01*
X508741Y838535D01*
X507889Y839040D01*
X506753Y839293D01*
X506090Y839797D01*
X505806Y840681D01*
X505995Y841565D01*
X506469Y842196D01*
X507131Y842575D01*
X507794D01*
X508457Y842323D01*
X509025Y841691D01*
G01X513381Y840050D02*
Y836515D01*
X513760Y835631D01*
X514328Y835126D01*
X514990Y835000D01*
X515653Y835126D01*
X516221Y835631D01*
X516600Y836515D01*
G01Y835000D02*
Y840050D01*
G01X521240Y835000D02*
Y840050D01*
G01Y839040D02*
X521713Y839545D01*
X522187Y839924D01*
X522850Y840050D01*
X523323Y839924D01*
X523891Y839545D01*
G01X529572Y835000D02*
Y841439D01*
X529762Y842070D01*
X530140Y842449D01*
X530709Y842575D01*
X531277Y842323D01*
X531561Y841691D01*
G01X530425Y839545D02*
X528531D01*
G01X539420Y835000D02*
Y840050D01*
G01Y839166D02*
X539041Y839671D01*
X538473Y839924D01*
X537810Y840050D01*
X537147Y839797D01*
X536579Y839293D01*
X536200Y838535D01*
X536011Y837525D01*
X536200Y836515D01*
X536579Y835757D01*
X537147Y835252D01*
X537810Y835000D01*
X538473Y835126D01*
X539041Y835505D01*
X539420Y836010D01*
G01X546805Y839419D02*
X546143Y839924D01*
X545575Y840050D01*
X544817Y839797D01*
X544249Y839293D01*
X543870Y838409D01*
X543775Y837525D01*
X543870Y836641D01*
X544249Y835884D01*
X544817Y835252D01*
X545575Y835000D01*
X546237Y835252D01*
X546805Y835757D01*
G01X551445Y838409D02*
X554475D01*
X554191Y839293D01*
X553718Y839797D01*
X553055Y840050D01*
X552392Y839924D01*
X551824Y839545D01*
X551445Y838661D01*
X551256Y837904D01*
Y837146D01*
X551445Y836389D01*
X551919Y835631D01*
X552487Y835126D01*
X553150Y835000D01*
X553812Y835252D01*
X554475Y836010D01*
G01X568015Y842575D02*
Y835000D01*
G01X566690Y840050D02*
X569341D01*
G01X574265Y835000D02*
Y840050D01*
G01Y839040D02*
X574738Y839545D01*
X575212Y839924D01*
X575875Y840050D01*
X576348Y839924D01*
X576916Y839545D01*
G01X581745Y838409D02*
X584775D01*
X584491Y839293D01*
X584018Y839797D01*
X583355Y840050D01*
X582692Y839924D01*
X582124Y839545D01*
X581745Y838661D01*
X581556Y837904D01*
Y837146D01*
X581745Y836389D01*
X582219Y835631D01*
X582787Y835126D01*
X583450Y835000D01*
X584112Y835252D01*
X584775Y836010D01*
G01X592445Y835000D02*
Y840050D01*
G01Y839166D02*
X592066Y839671D01*
X591498Y839924D01*
X590835Y840050D01*
X590172Y839797D01*
X589604Y839293D01*
X589225Y838535D01*
X589036Y837525D01*
X589225Y836515D01*
X589604Y835757D01*
X590172Y835252D01*
X590835Y835000D01*
X591498Y835126D01*
X592066Y835505D01*
X592445Y836010D01*
G01X598315Y842575D02*
Y835000D01*
G01X596990Y840050D02*
X599641D01*
G01X603050Y835000D02*
Y840050D01*
G01Y838661D02*
X603334Y839293D01*
X603807Y839797D01*
X604470Y840050D01*
X605133Y839797D01*
X605606Y839293D01*
X605890Y838661D01*
Y835000D01*
G01Y838661D02*
X606175Y839293D01*
X606648Y839797D01*
X607311Y840050D01*
X607974Y839797D01*
X608447Y839293D01*
X608731Y838535D01*
Y835000D01*
G01X612045Y838409D02*
X615075D01*
X614791Y839293D01*
X614318Y839797D01*
X613655Y840050D01*
X612992Y839924D01*
X612424Y839545D01*
X612045Y838661D01*
X611856Y837904D01*
Y837146D01*
X612045Y836389D01*
X612519Y835631D01*
X613087Y835126D01*
X613750Y835000D01*
X614412Y835252D01*
X615075Y836010D01*
G01X619431Y835000D02*
Y840050D01*
G01Y838787D02*
X619810Y839419D01*
X620378Y839924D01*
X621135Y840050D01*
X621798Y839924D01*
X622366Y839419D01*
X622650Y838535D01*
Y835000D01*
G01X628615Y842575D02*
Y835000D01*
G01X627290Y840050D02*
X629941D01*
G01X643765D02*
Y835000D01*
G01Y842070D02*
X643576Y842196D01*
Y842449D01*
X643765Y842575D01*
X643955Y842449D01*
Y842196D01*
X643765Y842070D01*
G01X649920Y835884D02*
X650394Y835379D01*
X651056Y835000D01*
X651625D01*
X652193Y835252D01*
X652571Y835631D01*
X652761Y836136D01*
X652666Y836894D01*
X652287Y837272D01*
X650583Y838030D01*
X650204Y838914D01*
X650394Y839545D01*
X650772Y839924D01*
X651340Y840050D01*
X651909Y839924D01*
X652477Y839545D01*
G01X666490Y840050D02*
Y835000D01*
G01Y842070D02*
X666301Y842196D01*
Y842449D01*
X666490Y842575D01*
X666680Y842449D01*
Y842196D01*
X666490Y842070D01*
G01X671225Y835000D02*
Y840050D01*
G01Y838661D02*
X671509Y839293D01*
X671982Y839797D01*
X672645Y840050D01*
X673308Y839797D01*
X673781Y839293D01*
X674065Y838661D01*
Y835000D01*
G01Y838661D02*
X674350Y839293D01*
X674823Y839797D01*
X675486Y840050D01*
X676149Y839797D01*
X676622Y839293D01*
X676906Y838535D01*
Y835000D01*
G01X678800D02*
Y840050D01*
G01Y838661D02*
X679084Y839293D01*
X679557Y839797D01*
X680220Y840050D01*
X680883Y839797D01*
X681356Y839293D01*
X681640Y838661D01*
Y835000D01*
G01Y838661D02*
X681925Y839293D01*
X682398Y839797D01*
X683061Y840050D01*
X683724Y839797D01*
X684197Y839293D01*
X684481Y838535D01*
Y835000D01*
G01X687795Y838409D02*
X690825D01*
X690541Y839293D01*
X690068Y839797D01*
X689405Y840050D01*
X688742Y839924D01*
X688174Y839545D01*
X687795Y838661D01*
X687606Y837904D01*
Y837146D01*
X687795Y836389D01*
X688269Y835631D01*
X688837Y835126D01*
X689500Y835000D01*
X690162Y835252D01*
X690825Y836010D01*
G01X695465Y835000D02*
Y840050D01*
G01Y839040D02*
X695938Y839545D01*
X696412Y839924D01*
X697075Y840050D01*
X697548Y839924D01*
X698116Y839545D01*
G01X702945Y835884D02*
X703419Y835379D01*
X704081Y835000D01*
X704650D01*
X705218Y835252D01*
X705596Y835631D01*
X705786Y836136D01*
X705691Y836894D01*
X705312Y837272D01*
X703608Y838030D01*
X703229Y838914D01*
X703419Y839545D01*
X703797Y839924D01*
X704365Y840050D01*
X704934Y839924D01*
X705502Y839545D01*
G01X711940Y840050D02*
Y835000D01*
G01Y842070D02*
X711751Y842196D01*
Y842449D01*
X711940Y842575D01*
X712130Y842449D01*
Y842196D01*
X711940Y842070D01*
G01X719515Y835000D02*
X718947Y835126D01*
X718379Y835631D01*
X718000Y836515D01*
X717811Y837525D01*
X718000Y838535D01*
X718379Y839419D01*
X718947Y839924D01*
X719515Y840050D01*
X720084Y839924D01*
X720652Y839419D01*
X721030Y838535D01*
X721125Y837525D01*
X721030Y836515D01*
X720652Y835631D01*
X720084Y835126D01*
X719515Y835000D01*
G01X725481D02*
Y840050D01*
G01Y838787D02*
X725860Y839419D01*
X726428Y839924D01*
X727185Y840050D01*
X727848Y839924D01*
X728416Y839419D01*
X728700Y838535D01*
Y835000D01*
G01X742809Y838787D02*
X744702D01*
Y836515D01*
X744134Y835757D01*
X743471Y835252D01*
X742525Y835000D01*
X741578Y835252D01*
X740915Y835757D01*
X740347Y836515D01*
X739968Y837399D01*
X739779Y838409D01*
Y839293D01*
X739968Y840050D01*
X740347Y840934D01*
X740915Y841691D01*
X741483Y842196D01*
X742240Y842575D01*
X742903D01*
X743661Y842323D01*
X744229Y841817D01*
G01X749815Y835000D02*
X749247Y835126D01*
X748679Y835631D01*
X748300Y836515D01*
X748111Y837525D01*
X748300Y838535D01*
X748679Y839419D01*
X749247Y839924D01*
X749815Y840050D01*
X750384Y839924D01*
X750952Y839419D01*
X751330Y838535D01*
X751425Y837525D01*
X751330Y836515D01*
X750952Y835631D01*
X750384Y835126D01*
X749815Y835000D01*
G01X757390D02*
Y842575D01*
G01X766670D02*
Y835000D01*
G01Y836136D02*
X766291Y835505D01*
X765723Y835126D01*
X765060Y835000D01*
X764303Y835252D01*
X763735Y835884D01*
X763356Y836641D01*
X763261Y837525D01*
X763356Y838409D01*
X763735Y839166D01*
X764303Y839797D01*
X765060Y840050D01*
X765723Y839924D01*
X766196Y839671D01*
X766670Y839166D01*
G01X772351Y833611D02*
X772730Y835252D01*
G01X782009Y835000D02*
X778222D01*
Y842575D01*
X782009D01*
G01X780494Y838914D02*
X778222D01*
G01X786081Y835000D02*
Y840050D01*
G01Y838787D02*
X786460Y839419D01*
X787028Y839924D01*
X787785Y840050D01*
X788448Y839924D01*
X789016Y839419D01*
X789300Y838535D01*
Y835000D01*
G01X795265Y842575D02*
Y835000D01*
G01X793940Y840050D02*
X796591D01*
G01X801420Y838409D02*
X804450D01*
X804166Y839293D01*
X803693Y839797D01*
X803030Y840050D01*
X802367Y839924D01*
X801799Y839545D01*
X801420Y838661D01*
X801231Y837904D01*
Y837146D01*
X801420Y836389D01*
X801894Y835631D01*
X802462Y835126D01*
X803125Y835000D01*
X803787Y835252D01*
X804450Y836010D01*
G01X808806Y835000D02*
Y842575D01*
G01X811836Y840050D02*
X808806Y837146D01*
G01X810037Y838282D02*
X812025Y835000D01*
G01X825565D02*
X824997Y835126D01*
X824429Y835631D01*
X824050Y836515D01*
X823861Y837525D01*
X824050Y838535D01*
X824429Y839419D01*
X824997Y839924D01*
X825565Y840050D01*
X826134Y839924D01*
X826702Y839419D01*
X827080Y838535D01*
X827175Y837525D01*
X827080Y836515D01*
X826702Y835631D01*
X826134Y835126D01*
X825565Y835000D01*
G01X831815D02*
Y840050D01*
G01Y839040D02*
X832288Y839545D01*
X832762Y839924D01*
X833425Y840050D01*
X833898Y839924D01*
X834466Y839545D01*
G01X847154Y842575D02*
X849427D01*
G01X848290D02*
Y835000D01*
G01X847154D02*
X849427D01*
G01X853025D02*
Y840050D01*
G01Y838661D02*
X853309Y839293D01*
X853782Y839797D01*
X854445Y840050D01*
X855108Y839797D01*
X855581Y839293D01*
X855865Y838661D01*
Y835000D01*
G01Y838661D02*
X856150Y839293D01*
X856623Y839797D01*
X857286Y840050D01*
X857949Y839797D01*
X858422Y839293D01*
X858706Y838535D01*
Y835000D01*
G01X861073D02*
X863440Y842575D01*
X865808Y835000D01*
G01X864955Y837651D02*
X861925D01*
G01X869690Y833106D02*
X870353Y832601D01*
X871110Y832475D01*
X871773Y832601D01*
X872341Y833232D01*
X872720Y834116D01*
Y840050D01*
G01Y839040D02*
X872341Y839545D01*
X871773Y839924D01*
X871110Y840050D01*
X870353Y839797D01*
X869879Y839293D01*
X869500Y838409D01*
X869311Y837525D01*
X869406Y836767D01*
X869785Y835884D01*
X870353Y835252D01*
X871110Y835000D01*
X871678Y835126D01*
X872341Y835631D01*
X872720Y836136D01*
G01X879064Y832475D02*
X880011Y833738D01*
X880484Y835000D01*
Y840050D01*
X880011Y841313D01*
X879064Y842575D01*
G01X499947Y823000D02*
Y830575D01*
X502219D01*
X502977Y830196D01*
X503545Y829313D01*
X503734Y828303D01*
X503545Y827293D01*
X503071Y826535D01*
X502219Y826156D01*
X499947D01*
G01X509415Y830575D02*
Y823000D01*
G01X507238Y830575D02*
X511593D01*
G01X515002Y823000D02*
Y830575D01*
G01X518979D02*
Y823000D01*
G01Y826787D02*
X515002D01*
G01X530531Y823000D02*
Y830575D01*
G01Y826914D02*
X531004Y827545D01*
X531478Y827924D01*
X532235Y828050D01*
X532803Y827924D01*
X533466Y827419D01*
X533750Y826661D01*
Y823000D01*
G01X539715D02*
X539147Y823126D01*
X538579Y823631D01*
X538200Y824515D01*
X538011Y825525D01*
X538200Y826535D01*
X538579Y827419D01*
X539147Y827924D01*
X539715Y828050D01*
X540284Y827924D01*
X540852Y827419D01*
X541230Y826535D01*
X541325Y825525D01*
X541230Y824515D01*
X540852Y823631D01*
X540284Y823126D01*
X539715Y823000D01*
G01X547290D02*
Y830575D01*
G01X553445Y826409D02*
X556475D01*
X556191Y827293D01*
X555718Y827797D01*
X555055Y828050D01*
X554392Y827924D01*
X553824Y827545D01*
X553445Y826661D01*
X553256Y825904D01*
Y825146D01*
X553445Y824389D01*
X553919Y823631D01*
X554487Y823126D01*
X555150Y823000D01*
X555812Y823252D01*
X556475Y824010D01*
G01X569447Y823000D02*
Y829439D01*
X569637Y830070D01*
X570015Y830449D01*
X570584Y830575D01*
X571152Y830323D01*
X571436Y829691D01*
G01X570300Y827545D02*
X568406D01*
G01X577590Y823000D02*
X577022Y823126D01*
X576454Y823631D01*
X576075Y824515D01*
X575886Y825525D01*
X576075Y826535D01*
X576454Y827419D01*
X577022Y827924D01*
X577590Y828050D01*
X578159Y827924D01*
X578727Y827419D01*
X579105Y826535D01*
X579200Y825525D01*
X579105Y824515D01*
X578727Y823631D01*
X578159Y823126D01*
X577590Y823000D01*
G01X583840D02*
Y828050D01*
G01Y827040D02*
X584313Y827545D01*
X584787Y827924D01*
X585450Y828050D01*
X585923Y827924D01*
X586491Y827545D01*
G01X601830Y827419D02*
X601168Y827924D01*
X600600Y828050D01*
X599842Y827797D01*
X599274Y827293D01*
X598895Y826409D01*
X598800Y825525D01*
X598895Y824641D01*
X599274Y823884D01*
X599842Y823252D01*
X600600Y823000D01*
X601262Y823252D01*
X601830Y823757D01*
G01X607890Y823000D02*
X607322Y823126D01*
X606754Y823631D01*
X606375Y824515D01*
X606186Y825525D01*
X606375Y826535D01*
X606754Y827419D01*
X607322Y827924D01*
X607890Y828050D01*
X608459Y827924D01*
X609027Y827419D01*
X609405Y826535D01*
X609500Y825525D01*
X609405Y824515D01*
X609027Y823631D01*
X608459Y823126D01*
X607890Y823000D01*
G01X612625D02*
Y828050D01*
G01Y826661D02*
X612909Y827293D01*
X613382Y827797D01*
X614045Y828050D01*
X614708Y827797D01*
X615181Y827293D01*
X615465Y826661D01*
Y823000D01*
G01Y826661D02*
X615750Y827293D01*
X616223Y827797D01*
X616886Y828050D01*
X617549Y827797D01*
X618022Y827293D01*
X618306Y826535D01*
Y823000D01*
G01X621336Y820475D02*
Y828050D01*
G01Y826914D02*
X621810Y827545D01*
X622283Y827924D01*
X623040Y828050D01*
X623703Y827924D01*
X624366Y827293D01*
X624650Y826409D01*
X624745Y825525D01*
X624650Y824641D01*
X624366Y823757D01*
X623798Y823252D01*
X623040Y823000D01*
X622378Y823126D01*
X621715Y823505D01*
X621336Y824010D01*
G01X630615Y823000D02*
X630047Y823126D01*
X629479Y823631D01*
X629100Y824515D01*
X628911Y825525D01*
X629100Y826535D01*
X629479Y827419D01*
X630047Y827924D01*
X630615Y828050D01*
X631184Y827924D01*
X631752Y827419D01*
X632130Y826535D01*
X632225Y825525D01*
X632130Y824515D01*
X631752Y823631D01*
X631184Y823126D01*
X630615Y823000D01*
G01X636581D02*
Y828050D01*
G01Y826787D02*
X636960Y827419D01*
X637528Y827924D01*
X638285Y828050D01*
X638948Y827924D01*
X639516Y827419D01*
X639800Y826535D01*
Y823000D01*
G01X644345Y826409D02*
X647375D01*
X647091Y827293D01*
X646618Y827797D01*
X645955Y828050D01*
X645292Y827924D01*
X644724Y827545D01*
X644345Y826661D01*
X644156Y825904D01*
Y825146D01*
X644345Y824389D01*
X644819Y823631D01*
X645387Y823126D01*
X646050Y823000D01*
X646712Y823252D01*
X647375Y824010D01*
G01X651731Y823000D02*
Y828050D01*
G01Y826787D02*
X652110Y827419D01*
X652678Y827924D01*
X653435Y828050D01*
X654098Y827924D01*
X654666Y827419D01*
X654950Y826535D01*
Y823000D01*
G01X660915Y830575D02*
Y823000D01*
G01X659590Y828050D02*
X662241D01*
G01X675592Y820475D02*
X674645Y821738D01*
X674172Y823000D01*
Y828050D01*
X674645Y829313D01*
X675592Y830575D01*
G01X683640Y823000D02*
Y830575D01*
X682504Y829060D01*
G01Y823000D02*
X684777D01*
G01X689416Y826156D02*
X690079Y827040D01*
X690647Y827545D01*
X691405Y827797D01*
X692068Y827545D01*
X692541Y827040D01*
X692920Y826282D01*
X693015Y825399D01*
X692920Y824641D01*
X692541Y823884D01*
X691973Y823252D01*
X691310Y823000D01*
X690553Y823252D01*
X689890Y824010D01*
X689511Y825146D01*
X689416Y826409D01*
X689606Y828050D01*
X689890Y828934D01*
X690363Y829817D01*
X691026Y830449D01*
X691689Y830575D01*
X692352Y830323D01*
X692825Y829691D01*
G01X695950Y823000D02*
Y828050D01*
G01Y826661D02*
X696234Y827293D01*
X696707Y827797D01*
X697370Y828050D01*
X698033Y827797D01*
X698506Y827293D01*
X698790Y826661D01*
Y823000D01*
G01Y826661D02*
X699075Y827293D01*
X699548Y827797D01*
X700211Y828050D01*
X700874Y827797D01*
X701347Y827293D01*
X701631Y826535D01*
Y823000D01*
G01X706365Y828050D02*
Y823000D01*
G01Y830070D02*
X706176Y830196D01*
Y830449D01*
X706365Y830575D01*
X706555Y830449D01*
Y830196D01*
X706365Y830070D01*
G01X713940Y823000D02*
Y830575D01*
G01X730984Y823000D02*
X727197Y825525D01*
X730984Y828050D01*
G01X742820Y823884D02*
X743294Y823379D01*
X743956Y823000D01*
X744525D01*
X745093Y823252D01*
X745471Y823631D01*
X745661Y824136D01*
X745566Y824894D01*
X745187Y825272D01*
X743483Y826030D01*
X743104Y826914D01*
X743294Y827545D01*
X743672Y827924D01*
X744240Y828050D01*
X744809Y827924D01*
X745377Y827545D01*
G01X751815Y828050D02*
Y823000D01*
G01Y830070D02*
X751626Y830196D01*
Y830449D01*
X751815Y830575D01*
X752005Y830449D01*
Y830196D01*
X751815Y830070D01*
G01X757970Y828050D02*
X760811D01*
X757970Y823000D01*
X760811D01*
G01X765545Y826409D02*
X768575D01*
X768291Y827293D01*
X767818Y827797D01*
X767155Y828050D01*
X766492Y827924D01*
X765924Y827545D01*
X765545Y826661D01*
X765356Y825904D01*
Y825146D01*
X765545Y824389D01*
X766019Y823631D01*
X766587Y823126D01*
X767250Y823000D01*
X767912Y823252D01*
X768575Y824010D01*
G01X784009Y823000D02*
X780222Y825525D01*
X784009Y828050D01*
G01X789690Y823000D02*
Y830575D01*
X788554Y829060D01*
G01Y823000D02*
X790827D01*
G01X795656Y823884D02*
X796319Y823252D01*
X797076Y823000D01*
X797834Y823252D01*
X798496Y824010D01*
X798970Y825146D01*
X799159Y826282D01*
Y827671D01*
X798970Y828807D01*
X798496Y829817D01*
X797928Y830323D01*
X797265Y830575D01*
X796508Y830323D01*
X795940Y829817D01*
X795561Y829060D01*
X795372Y828050D01*
X795561Y827166D01*
X796035Y826282D01*
X796603Y825777D01*
X797265Y825651D01*
X798023Y825904D01*
X798591Y826535D01*
X799159Y827671D01*
G01X804651Y823000D02*
X804840Y824641D01*
X805125Y826030D01*
X805503Y827293D01*
X805977Y828681D01*
X806734Y830575D01*
X802947D01*
G01X809575Y823000D02*
Y828050D01*
G01Y826661D02*
X809859Y827293D01*
X810332Y827797D01*
X810995Y828050D01*
X811658Y827797D01*
X812131Y827293D01*
X812415Y826661D01*
Y823000D01*
G01Y826661D02*
X812700Y827293D01*
X813173Y827797D01*
X813836Y828050D01*
X814499Y827797D01*
X814972Y827293D01*
X815256Y826535D01*
Y823000D01*
G01X819990Y828050D02*
Y823000D01*
G01Y830070D02*
X819801Y830196D01*
Y830449D01*
X819990Y830575D01*
X820180Y830449D01*
Y830196D01*
X819990Y830070D01*
G01X827565Y823000D02*
Y830575D01*
G01X835614Y820475D02*
X836561Y821738D01*
X837034Y823000D01*
Y828050D01*
X836561Y829313D01*
X835614Y830575D01*
G01X499447Y848000D02*
Y855575D01*
X501719D01*
X502477Y855196D01*
X503045Y854313D01*
X503234Y853303D01*
X503045Y852293D01*
X502571Y851535D01*
X501719Y851156D01*
X499447D01*
G01X508915Y855575D02*
Y848000D01*
G01X506738Y855575D02*
X511093D01*
G01X514502Y848000D02*
Y855575D01*
G01X518479D02*
Y848000D01*
G01Y851787D02*
X514502D01*
G01X530031Y848000D02*
Y855575D01*
G01Y851914D02*
X530504Y852545D01*
X530978Y852924D01*
X531735Y853050D01*
X532303Y852924D01*
X532966Y852419D01*
X533250Y851661D01*
Y848000D01*
G01X539215D02*
X538647Y848126D01*
X538079Y848631D01*
X537700Y849515D01*
X537511Y850525D01*
X537700Y851535D01*
X538079Y852419D01*
X538647Y852924D01*
X539215Y853050D01*
X539784Y852924D01*
X540352Y852419D01*
X540730Y851535D01*
X540825Y850525D01*
X540730Y849515D01*
X540352Y848631D01*
X539784Y848126D01*
X539215Y848000D01*
G01X546790D02*
Y855575D01*
G01X552945Y851409D02*
X555975D01*
X555691Y852293D01*
X555218Y852797D01*
X554555Y853050D01*
X553892Y852924D01*
X553324Y852545D01*
X552945Y851661D01*
X552756Y850904D01*
Y850146D01*
X552945Y849389D01*
X553419Y848631D01*
X553987Y848126D01*
X554650Y848000D01*
X555312Y848252D01*
X555975Y849010D01*
G01X568947Y848000D02*
Y854439D01*
X569137Y855070D01*
X569515Y855449D01*
X570084Y855575D01*
X570652Y855323D01*
X570936Y854691D01*
G01X569800Y852545D02*
X567906D01*
G01X577090Y848000D02*
X576522Y848126D01*
X575954Y848631D01*
X575575Y849515D01*
X575386Y850525D01*
X575575Y851535D01*
X575954Y852419D01*
X576522Y852924D01*
X577090Y853050D01*
X577659Y852924D01*
X578227Y852419D01*
X578605Y851535D01*
X578700Y850525D01*
X578605Y849515D01*
X578227Y848631D01*
X577659Y848126D01*
X577090Y848000D01*
G01X583340D02*
Y853050D01*
G01Y852040D02*
X583813Y852545D01*
X584287Y852924D01*
X584950Y853050D01*
X585423Y852924D01*
X585991Y852545D01*
G01X601330Y852419D02*
X600668Y852924D01*
X600100Y853050D01*
X599342Y852797D01*
X598774Y852293D01*
X598395Y851409D01*
X598300Y850525D01*
X598395Y849641D01*
X598774Y848884D01*
X599342Y848252D01*
X600100Y848000D01*
X600762Y848252D01*
X601330Y848757D01*
G01X607390Y848000D02*
X606822Y848126D01*
X606254Y848631D01*
X605875Y849515D01*
X605686Y850525D01*
X605875Y851535D01*
X606254Y852419D01*
X606822Y852924D01*
X607390Y853050D01*
X607959Y852924D01*
X608527Y852419D01*
X608905Y851535D01*
X609000Y850525D01*
X608905Y849515D01*
X608527Y848631D01*
X607959Y848126D01*
X607390Y848000D01*
G01X612125D02*
Y853050D01*
G01Y851661D02*
X612409Y852293D01*
X612882Y852797D01*
X613545Y853050D01*
X614208Y852797D01*
X614681Y852293D01*
X614965Y851661D01*
Y848000D01*
G01Y851661D02*
X615250Y852293D01*
X615723Y852797D01*
X616386Y853050D01*
X617049Y852797D01*
X617522Y852293D01*
X617806Y851535D01*
Y848000D01*
G01X620836Y845475D02*
Y853050D01*
G01Y851914D02*
X621310Y852545D01*
X621783Y852924D01*
X622540Y853050D01*
X623203Y852924D01*
X623866Y852293D01*
X624150Y851409D01*
X624245Y850525D01*
X624150Y849641D01*
X623866Y848757D01*
X623298Y848252D01*
X622540Y848000D01*
X621878Y848126D01*
X621215Y848505D01*
X620836Y849010D01*
G01X630115Y848000D02*
X629547Y848126D01*
X628979Y848631D01*
X628600Y849515D01*
X628411Y850525D01*
X628600Y851535D01*
X628979Y852419D01*
X629547Y852924D01*
X630115Y853050D01*
X630684Y852924D01*
X631252Y852419D01*
X631630Y851535D01*
X631725Y850525D01*
X631630Y849515D01*
X631252Y848631D01*
X630684Y848126D01*
X630115Y848000D01*
G01X636081D02*
Y853050D01*
G01Y851787D02*
X636460Y852419D01*
X637028Y852924D01*
X637785Y853050D01*
X638448Y852924D01*
X639016Y852419D01*
X639300Y851535D01*
Y848000D01*
G01X643845Y851409D02*
X646875D01*
X646591Y852293D01*
X646118Y852797D01*
X645455Y853050D01*
X644792Y852924D01*
X644224Y852545D01*
X643845Y851661D01*
X643656Y850904D01*
Y850146D01*
X643845Y849389D01*
X644319Y848631D01*
X644887Y848126D01*
X645550Y848000D01*
X646212Y848252D01*
X646875Y849010D01*
G01X651231Y848000D02*
Y853050D01*
G01Y851787D02*
X651610Y852419D01*
X652178Y852924D01*
X652935Y853050D01*
X653598Y852924D01*
X654166Y852419D01*
X654450Y851535D01*
Y848000D01*
G01X660415Y855575D02*
Y848000D01*
G01X659090Y853050D02*
X661741D01*
G01X675092Y845475D02*
X674145Y846738D01*
X673672Y848000D01*
Y853050D01*
X674145Y854313D01*
X675092Y855575D01*
G01X683140Y848000D02*
Y855575D01*
X682004Y854060D01*
G01Y848000D02*
X684277D01*
G01X688916Y851156D02*
X689579Y852040D01*
X690147Y852545D01*
X690905Y852797D01*
X691568Y852545D01*
X692041Y852040D01*
X692420Y851282D01*
X692515Y850399D01*
X692420Y849641D01*
X692041Y848884D01*
X691473Y848252D01*
X690810Y848000D01*
X690053Y848252D01*
X689390Y849010D01*
X689011Y850146D01*
X688916Y851409D01*
X689106Y853050D01*
X689390Y853934D01*
X689863Y854817D01*
X690526Y855449D01*
X691189Y855575D01*
X691852Y855323D01*
X692325Y854691D01*
G01X695450Y848000D02*
Y853050D01*
G01Y851661D02*
X695734Y852293D01*
X696207Y852797D01*
X696870Y853050D01*
X697533Y852797D01*
X698006Y852293D01*
X698290Y851661D01*
Y848000D01*
G01Y851661D02*
X698575Y852293D01*
X699048Y852797D01*
X699711Y853050D01*
X700374Y852797D01*
X700847Y852293D01*
X701131Y851535D01*
Y848000D01*
G01X705865Y853050D02*
Y848000D01*
G01Y855070D02*
X705676Y855196D01*
Y855449D01*
X705865Y855575D01*
X706055Y855449D01*
Y855196D01*
X705865Y855070D01*
G01X713440Y848000D02*
Y855575D01*
G01X730484Y848000D02*
X726697Y850525D01*
X730484Y853050D01*
G01X742320Y848884D02*
X742794Y848379D01*
X743456Y848000D01*
X744025D01*
X744593Y848252D01*
X744971Y848631D01*
X745161Y849136D01*
X745066Y849894D01*
X744687Y850272D01*
X742983Y851030D01*
X742604Y851914D01*
X742794Y852545D01*
X743172Y852924D01*
X743740Y853050D01*
X744309Y852924D01*
X744877Y852545D01*
G01X751315Y853050D02*
Y848000D01*
G01Y855070D02*
X751126Y855196D01*
Y855449D01*
X751315Y855575D01*
X751505Y855449D01*
Y855196D01*
X751315Y855070D01*
G01X757470Y853050D02*
X760311D01*
X757470Y848000D01*
X760311D01*
G01X765045Y851409D02*
X768075D01*
X767791Y852293D01*
X767318Y852797D01*
X766655Y853050D01*
X765992Y852924D01*
X765424Y852545D01*
X765045Y851661D01*
X764856Y850904D01*
Y850146D01*
X765045Y849389D01*
X765519Y848631D01*
X766087Y848126D01*
X766750Y848000D01*
X767412Y848252D01*
X768075Y849010D01*
G01X783509Y848000D02*
X779722Y850525D01*
X783509Y853050D01*
G01X789190Y848000D02*
Y855575D01*
X788054Y854060D01*
G01Y848000D02*
X790327D01*
G01X795156Y848884D02*
X795819Y848252D01*
X796576Y848000D01*
X797334Y848252D01*
X797996Y849010D01*
X798470Y850146D01*
X798659Y851282D01*
Y852671D01*
X798470Y853807D01*
X797996Y854817D01*
X797428Y855323D01*
X796765Y855575D01*
X796008Y855323D01*
X795440Y854817D01*
X795061Y854060D01*
X794872Y853050D01*
X795061Y852166D01*
X795535Y851282D01*
X796103Y850777D01*
X796765Y850651D01*
X797523Y850904D01*
X798091Y851535D01*
X798659Y852671D01*
G01X804151Y848000D02*
X804340Y849641D01*
X804625Y851030D01*
X805003Y852293D01*
X805477Y853681D01*
X806234Y855575D01*
X802447D01*
G01X809075Y848000D02*
Y853050D01*
G01Y851661D02*
X809359Y852293D01*
X809832Y852797D01*
X810495Y853050D01*
X811158Y852797D01*
X811631Y852293D01*
X811915Y851661D01*
Y848000D01*
G01Y851661D02*
X812200Y852293D01*
X812673Y852797D01*
X813336Y853050D01*
X813999Y852797D01*
X814472Y852293D01*
X814756Y851535D01*
Y848000D01*
G01X819490Y853050D02*
Y848000D01*
G01Y855070D02*
X819301Y855196D01*
Y855449D01*
X819490Y855575D01*
X819680Y855449D01*
Y855196D01*
X819490Y855070D01*
G01X827065Y848000D02*
Y855575D01*
G01X835114Y845475D02*
X836061Y846738D01*
X836534Y848000D01*
Y853050D01*
X836061Y854313D01*
X835114Y855575D01*
G01X498947Y868075D02*
Y860500D01*
X502734D01*
G01X510120D02*
Y865550D01*
G01Y864666D02*
X509741Y865171D01*
X509173Y865424D01*
X508510Y865550D01*
X507847Y865297D01*
X507279Y864793D01*
X506900Y864035D01*
X506711Y863025D01*
X506900Y862015D01*
X507279Y861257D01*
X507847Y860752D01*
X508510Y860500D01*
X509173Y860626D01*
X509741Y861005D01*
X510120Y861510D01*
G01X514570Y861384D02*
X515044Y860879D01*
X515706Y860500D01*
X516275D01*
X516843Y860752D01*
X517221Y861131D01*
X517411Y861636D01*
X517316Y862394D01*
X516937Y862772D01*
X515233Y863530D01*
X514854Y864414D01*
X515044Y865045D01*
X515422Y865424D01*
X515990Y865550D01*
X516559Y865424D01*
X517127Y865045D01*
G01X522145Y863909D02*
X525175D01*
X524891Y864793D01*
X524418Y865297D01*
X523755Y865550D01*
X523092Y865424D01*
X522524Y865045D01*
X522145Y864161D01*
X521956Y863404D01*
Y862646D01*
X522145Y861889D01*
X522619Y861131D01*
X523187Y860626D01*
X523850Y860500D01*
X524512Y860752D01*
X525175Y861510D01*
G01X529815Y860500D02*
Y865550D01*
G01Y864540D02*
X530288Y865045D01*
X530762Y865424D01*
X531425Y865550D01*
X531898Y865424D01*
X532466Y865045D01*
G01X544586Y865550D02*
X546290Y860500D01*
X547995Y865550D01*
G01X553865D02*
Y860500D01*
G01Y867570D02*
X553676Y867696D01*
Y867949D01*
X553865Y868075D01*
X554055Y867949D01*
Y867696D01*
X553865Y867570D01*
G01X563145Y860500D02*
Y865550D01*
G01Y864666D02*
X562766Y865171D01*
X562198Y865424D01*
X561535Y865550D01*
X560872Y865297D01*
X560304Y864793D01*
X559925Y864035D01*
X559736Y863025D01*
X559925Y862015D01*
X560304Y861257D01*
X560872Y860752D01*
X561535Y860500D01*
X562198Y860626D01*
X562766Y861005D01*
X563145Y861510D01*
G01X574981Y860500D02*
Y868075D01*
G01Y864414D02*
X575454Y865045D01*
X575928Y865424D01*
X576685Y865550D01*
X577253Y865424D01*
X577916Y864919D01*
X578200Y864161D01*
Y860500D01*
G01X584165D02*
X583597Y860626D01*
X583029Y861131D01*
X582650Y862015D01*
X582461Y863025D01*
X582650Y864035D01*
X583029Y864919D01*
X583597Y865424D01*
X584165Y865550D01*
X584734Y865424D01*
X585302Y864919D01*
X585680Y864035D01*
X585775Y863025D01*
X585680Y862015D01*
X585302Y861131D01*
X584734Y860626D01*
X584165Y860500D01*
G01X591740D02*
Y868075D01*
G01X597895Y863909D02*
X600925D01*
X600641Y864793D01*
X600168Y865297D01*
X599505Y865550D01*
X598842Y865424D01*
X598274Y865045D01*
X597895Y864161D01*
X597706Y863404D01*
Y862646D01*
X597895Y861889D01*
X598369Y861131D01*
X598937Y860626D01*
X599600Y860500D01*
X600262Y860752D01*
X600925Y861510D01*
G01X613992Y857975D02*
X613045Y859238D01*
X612572Y860500D01*
Y865550D01*
X613045Y866813D01*
X613992Y868075D01*
G01X620336Y860500D02*
Y868075D01*
G01Y864287D02*
X620810Y865045D01*
X621378Y865424D01*
X621946Y865550D01*
X622798Y865297D01*
X623366Y864793D01*
X623745Y863909D01*
Y862899D01*
X623555Y861889D01*
X623177Y861131D01*
X622514Y860626D01*
X621946Y860500D01*
X621378Y860626D01*
X620810Y861005D01*
X620336Y861636D01*
G01X628195Y863909D02*
X631225D01*
X630941Y864793D01*
X630468Y865297D01*
X629805Y865550D01*
X629142Y865424D01*
X628574Y865045D01*
X628195Y864161D01*
X628006Y863404D01*
Y862646D01*
X628195Y861889D01*
X628669Y861131D01*
X629237Y860626D01*
X629900Y860500D01*
X630562Y860752D01*
X631225Y861510D01*
G01X636622Y860500D02*
Y866939D01*
X636812Y867570D01*
X637190Y867949D01*
X637759Y868075D01*
X638327Y867823D01*
X638611Y867191D01*
G01X637475Y865045D02*
X635581D01*
G01X644765Y860500D02*
X644197Y860626D01*
X643629Y861131D01*
X643250Y862015D01*
X643061Y863025D01*
X643250Y864035D01*
X643629Y864919D01*
X644197Y865424D01*
X644765Y865550D01*
X645334Y865424D01*
X645902Y864919D01*
X646280Y864035D01*
X646375Y863025D01*
X646280Y862015D01*
X645902Y861131D01*
X645334Y860626D01*
X644765Y860500D01*
G01X651015D02*
Y865550D01*
G01Y864540D02*
X651488Y865045D01*
X651962Y865424D01*
X652625Y865550D01*
X653098Y865424D01*
X653666Y865045D01*
G01X658495Y863909D02*
X661525D01*
X661241Y864793D01*
X660768Y865297D01*
X660105Y865550D01*
X659442Y865424D01*
X658874Y865045D01*
X658495Y864161D01*
X658306Y863404D01*
Y862646D01*
X658495Y861889D01*
X658969Y861131D01*
X659537Y860626D01*
X660200Y860500D01*
X660862Y860752D01*
X661525Y861510D01*
G01X675065Y868075D02*
Y860500D01*
G01X673740Y865550D02*
X676391D01*
G01X681031Y860500D02*
Y868075D01*
G01Y864414D02*
X681504Y865045D01*
X681978Y865424D01*
X682735Y865550D01*
X683303Y865424D01*
X683966Y864919D01*
X684250Y864161D01*
Y860500D01*
G01X688795Y863909D02*
X691825D01*
X691541Y864793D01*
X691068Y865297D01*
X690405Y865550D01*
X689742Y865424D01*
X689174Y865045D01*
X688795Y864161D01*
X688606Y863404D01*
Y862646D01*
X688795Y861889D01*
X689269Y861131D01*
X689837Y860626D01*
X690500Y860500D01*
X691162Y860752D01*
X691825Y861510D01*
G01X706880Y864919D02*
X706218Y865424D01*
X705650Y865550D01*
X704892Y865297D01*
X704324Y864793D01*
X703945Y863909D01*
X703850Y863025D01*
X703945Y862141D01*
X704324Y861384D01*
X704892Y860752D01*
X705650Y860500D01*
X706312Y860752D01*
X706880Y861257D01*
G01X712940Y860500D02*
X712372Y860626D01*
X711804Y861131D01*
X711425Y862015D01*
X711236Y863025D01*
X711425Y864035D01*
X711804Y864919D01*
X712372Y865424D01*
X712940Y865550D01*
X713509Y865424D01*
X714077Y864919D01*
X714455Y864035D01*
X714550Y863025D01*
X714455Y862015D01*
X714077Y861131D01*
X713509Y860626D01*
X712940Y860500D01*
G01X718811Y857975D02*
Y865550D01*
G01Y864414D02*
X719285Y865045D01*
X719758Y865424D01*
X720515Y865550D01*
X721178Y865424D01*
X721841Y864793D01*
X722125Y863909D01*
X722220Y863025D01*
X722125Y862141D01*
X721841Y861257D01*
X721273Y860752D01*
X720515Y860500D01*
X719853Y860626D01*
X719190Y861005D01*
X718811Y861510D01*
G01X726386Y857975D02*
Y865550D01*
G01Y864414D02*
X726860Y865045D01*
X727333Y865424D01*
X728090Y865550D01*
X728753Y865424D01*
X729416Y864793D01*
X729700Y863909D01*
X729795Y863025D01*
X729700Y862141D01*
X729416Y861257D01*
X728848Y860752D01*
X728090Y860500D01*
X727428Y860626D01*
X726765Y861005D01*
X726386Y861510D01*
G01X734245Y863909D02*
X737275D01*
X736991Y864793D01*
X736518Y865297D01*
X735855Y865550D01*
X735192Y865424D01*
X734624Y865045D01*
X734245Y864161D01*
X734056Y863404D01*
Y862646D01*
X734245Y861889D01*
X734719Y861131D01*
X735287Y860626D01*
X735950Y860500D01*
X736612Y860752D01*
X737275Y861510D01*
G01X741915Y860500D02*
Y865550D01*
G01Y864540D02*
X742388Y865045D01*
X742862Y865424D01*
X743525Y865550D01*
X743998Y865424D01*
X744566Y865045D01*
G01X756686Y857975D02*
Y865550D01*
G01Y864414D02*
X757160Y865045D01*
X757633Y865424D01*
X758390Y865550D01*
X759053Y865424D01*
X759716Y864793D01*
X760000Y863909D01*
X760095Y863025D01*
X760000Y862141D01*
X759716Y861257D01*
X759148Y860752D01*
X758390Y860500D01*
X757728Y860626D01*
X757065Y861005D01*
X756686Y861510D01*
G01X765965Y860500D02*
Y868075D01*
G01X775245Y860500D02*
Y865550D01*
G01Y864666D02*
X774866Y865171D01*
X774298Y865424D01*
X773635Y865550D01*
X772972Y865297D01*
X772404Y864793D01*
X772025Y864035D01*
X771836Y863025D01*
X772025Y862015D01*
X772404Y861257D01*
X772972Y860752D01*
X773635Y860500D01*
X774298Y860626D01*
X774866Y861005D01*
X775245Y861510D01*
G01X781115Y868075D02*
Y860500D01*
G01X779790Y865550D02*
X782441D01*
G01X788690D02*
Y860500D01*
G01Y867570D02*
X788501Y867696D01*
Y867949D01*
X788690Y868075D01*
X788880Y867949D01*
Y867696D01*
X788690Y867570D01*
G01X794656Y860500D02*
Y865550D01*
G01Y864287D02*
X795035Y864919D01*
X795603Y865424D01*
X796360Y865550D01*
X797023Y865424D01*
X797591Y864919D01*
X797875Y864035D01*
Y860500D01*
G01X802515Y858606D02*
X803178Y858101D01*
X803935Y857975D01*
X804598Y858101D01*
X805166Y858732D01*
X805545Y859616D01*
Y865550D01*
G01Y864540D02*
X805166Y865045D01*
X804598Y865424D01*
X803935Y865550D01*
X803178Y865297D01*
X802704Y864793D01*
X802325Y863909D01*
X802136Y863025D01*
X802231Y862267D01*
X802610Y861384D01*
X803178Y860752D01*
X803935Y860500D01*
X804503Y860626D01*
X805166Y861131D01*
X805545Y861636D01*
G01X811889Y857975D02*
X812836Y859238D01*
X813309Y860500D01*
Y865550D01*
X812836Y866813D01*
X811889Y868075D01*
G01X498473Y880575D02*
X500840Y873000D01*
X503208Y880575D01*
G01X508415Y878050D02*
Y873000D01*
G01Y880070D02*
X508226Y880196D01*
Y880449D01*
X508415Y880575D01*
X508605Y880449D01*
Y880196D01*
X508415Y880070D01*
G01X517695Y873000D02*
Y878050D01*
G01Y877166D02*
X517316Y877671D01*
X516748Y877924D01*
X516085Y878050D01*
X515422Y877797D01*
X514854Y877293D01*
X514475Y876535D01*
X514286Y875525D01*
X514475Y874515D01*
X514854Y873757D01*
X515422Y873252D01*
X516085Y873000D01*
X516748Y873126D01*
X517316Y873505D01*
X517695Y874010D01*
G01X529152Y873000D02*
Y880575D01*
G01X533129D02*
Y873000D01*
G01Y876787D02*
X529152D01*
G01X538715Y873000D02*
X538147Y873126D01*
X537579Y873631D01*
X537200Y874515D01*
X537011Y875525D01*
X537200Y876535D01*
X537579Y877419D01*
X538147Y877924D01*
X538715Y878050D01*
X539284Y877924D01*
X539852Y877419D01*
X540230Y876535D01*
X540325Y875525D01*
X540230Y874515D01*
X539852Y873631D01*
X539284Y873126D01*
X538715Y873000D01*
G01X546290D02*
Y880575D01*
G01X552445Y876409D02*
X555475D01*
X555191Y877293D01*
X554718Y877797D01*
X554055Y878050D01*
X553392Y877924D01*
X552824Y877545D01*
X552445Y876661D01*
X552256Y875904D01*
Y875146D01*
X552445Y874389D01*
X552919Y873631D01*
X553487Y873126D01*
X554150Y873000D01*
X554812Y873252D01*
X555475Y874010D01*
G01X568542Y870475D02*
X567595Y871738D01*
X567122Y873000D01*
Y878050D01*
X567595Y879313D01*
X568542Y880575D01*
G01X574981Y873000D02*
Y880575D01*
G01Y876914D02*
X575454Y877545D01*
X575928Y877924D01*
X576685Y878050D01*
X577253Y877924D01*
X577916Y877419D01*
X578200Y876661D01*
Y873000D01*
G01X584165D02*
X583597Y873126D01*
X583029Y873631D01*
X582650Y874515D01*
X582461Y875525D01*
X582650Y876535D01*
X583029Y877419D01*
X583597Y877924D01*
X584165Y878050D01*
X584734Y877924D01*
X585302Y877419D01*
X585680Y876535D01*
X585775Y875525D01*
X585680Y874515D01*
X585302Y873631D01*
X584734Y873126D01*
X584165Y873000D01*
G01X591740D02*
Y880575D01*
G01X597895Y876409D02*
X600925D01*
X600641Y877293D01*
X600168Y877797D01*
X599505Y878050D01*
X598842Y877924D01*
X598274Y877545D01*
X597895Y876661D01*
X597706Y875904D01*
Y875146D01*
X597895Y874389D01*
X598369Y873631D01*
X598937Y873126D01*
X599600Y873000D01*
X600262Y873252D01*
X600925Y874010D01*
G01X613045Y873884D02*
X613519Y873379D01*
X614181Y873000D01*
X614750D01*
X615318Y873252D01*
X615696Y873631D01*
X615886Y874136D01*
X615791Y874894D01*
X615412Y875272D01*
X613708Y876030D01*
X613329Y876914D01*
X613519Y877545D01*
X613897Y877924D01*
X614465Y878050D01*
X615034Y877924D01*
X615602Y877545D01*
G01X622040Y878050D02*
Y873000D01*
G01Y880070D02*
X621851Y880196D01*
Y880449D01*
X622040Y880575D01*
X622230Y880449D01*
Y880196D01*
X622040Y880070D01*
G01X628195Y878050D02*
X631036D01*
X628195Y873000D01*
X631036D01*
G01X635770Y876409D02*
X638800D01*
X638516Y877293D01*
X638043Y877797D01*
X637380Y878050D01*
X636717Y877924D01*
X636149Y877545D01*
X635770Y876661D01*
X635581Y875904D01*
Y875146D01*
X635770Y874389D01*
X636244Y873631D01*
X636812Y873126D01*
X637475Y873000D01*
X638137Y873252D01*
X638800Y874010D01*
G01X654234Y873000D02*
X650447Y875525D01*
X654234Y878050D01*
G01X658685Y874389D02*
X661146D01*
G01Y876661D02*
X658685D01*
G01X667490Y873000D02*
Y880575D01*
X666354Y879060D01*
G01Y873000D02*
X668627D01*
G01X673266Y876156D02*
X673929Y877040D01*
X674497Y877545D01*
X675255Y877797D01*
X675918Y877545D01*
X676391Y877040D01*
X676770Y876282D01*
X676865Y875399D01*
X676770Y874641D01*
X676391Y873884D01*
X675823Y873252D01*
X675160Y873000D01*
X674403Y873252D01*
X673740Y874010D01*
X673361Y875146D01*
X673266Y876409D01*
X673456Y878050D01*
X673740Y878934D01*
X674213Y879817D01*
X674876Y880449D01*
X675539Y880575D01*
X676202Y880323D01*
X676675Y879691D01*
G01X687375Y873000D02*
Y878050D01*
G01Y876661D02*
X687659Y877293D01*
X688132Y877797D01*
X688795Y878050D01*
X689458Y877797D01*
X689931Y877293D01*
X690215Y876661D01*
Y873000D01*
G01Y876661D02*
X690500Y877293D01*
X690973Y877797D01*
X691636Y878050D01*
X692299Y877797D01*
X692772Y877293D01*
X693056Y876535D01*
Y873000D01*
G01X697790Y878050D02*
Y873000D01*
G01Y880070D02*
X697601Y880196D01*
Y880449D01*
X697790Y880575D01*
X697980Y880449D01*
Y880196D01*
X697790Y880070D01*
G01X705365Y873000D02*
Y880575D01*
G01X713414Y870475D02*
X714361Y871738D01*
X714834Y873000D01*
Y878050D01*
X714361Y879313D01*
X713414Y880575D01*
G01X513340Y893075D02*
Y885500D01*
G01X512015Y890550D02*
X514666D01*
G01X519306Y885500D02*
Y893075D01*
G01Y889414D02*
X519779Y890045D01*
X520253Y890424D01*
X521010Y890550D01*
X521578Y890424D01*
X522241Y889919D01*
X522525Y889161D01*
Y885500D01*
G01X527070Y888909D02*
X530100D01*
X529816Y889793D01*
X529343Y890297D01*
X528680Y890550D01*
X528017Y890424D01*
X527449Y890045D01*
X527070Y889161D01*
X526881Y888404D01*
Y887646D01*
X527070Y886889D01*
X527544Y886131D01*
X528112Y885626D01*
X528775Y885500D01*
X529437Y885752D01*
X530100Y886510D01*
G01X542315Y885500D02*
Y890550D01*
G01Y889540D02*
X542788Y890045D01*
X543262Y890424D01*
X543925Y890550D01*
X544398Y890424D01*
X544966Y890045D01*
G01X549795Y888909D02*
X552825D01*
X552541Y889793D01*
X552068Y890297D01*
X551405Y890550D01*
X550742Y890424D01*
X550174Y890045D01*
X549795Y889161D01*
X549606Y888404D01*
Y887646D01*
X549795Y886889D01*
X550269Y886131D01*
X550837Y885626D01*
X551500Y885500D01*
X552162Y885752D01*
X552825Y886510D01*
G01X558790Y885500D02*
Y893075D01*
G01X568070Y885500D02*
Y890550D01*
G01Y889666D02*
X567691Y890171D01*
X567123Y890424D01*
X566460Y890550D01*
X565797Y890297D01*
X565229Y889793D01*
X564850Y889035D01*
X564661Y888025D01*
X564850Y887015D01*
X565229Y886257D01*
X565797Y885752D01*
X566460Y885500D01*
X567123Y885626D01*
X567691Y886005D01*
X568070Y886510D01*
G01X573940Y893075D02*
Y885500D01*
G01X572615Y890550D02*
X575266D01*
G01X581515D02*
Y885500D01*
G01Y892570D02*
X581326Y892696D01*
Y892949D01*
X581515Y893075D01*
X581705Y892949D01*
Y892696D01*
X581515Y892570D01*
G01X587386Y890550D02*
X589090Y885500D01*
X590795Y890550D01*
G01X595245Y888909D02*
X598275D01*
X597991Y889793D01*
X597518Y890297D01*
X596855Y890550D01*
X596192Y890424D01*
X595624Y890045D01*
X595245Y889161D01*
X595056Y888404D01*
Y887646D01*
X595245Y886889D01*
X595719Y886131D01*
X596287Y885626D01*
X596950Y885500D01*
X597612Y885752D01*
X598275Y886510D01*
G01X611815Y885500D02*
Y893075D01*
G01X619390Y885500D02*
X618822Y885626D01*
X618254Y886131D01*
X617875Y887015D01*
X617686Y888025D01*
X617875Y889035D01*
X618254Y889919D01*
X618822Y890424D01*
X619390Y890550D01*
X619959Y890424D01*
X620527Y889919D01*
X620905Y889035D01*
X621000Y888025D01*
X620905Y887015D01*
X620527Y886131D01*
X619959Y885626D01*
X619390Y885500D01*
G01X628480Y889919D02*
X627818Y890424D01*
X627250Y890550D01*
X626492Y890297D01*
X625924Y889793D01*
X625545Y888909D01*
X625450Y888025D01*
X625545Y887141D01*
X625924Y886384D01*
X626492Y885752D01*
X627250Y885500D01*
X627912Y885752D01*
X628480Y886257D01*
G01X636245Y885500D02*
Y890550D01*
G01Y889666D02*
X635866Y890171D01*
X635298Y890424D01*
X634635Y890550D01*
X633972Y890297D01*
X633404Y889793D01*
X633025Y889035D01*
X632836Y888025D01*
X633025Y887015D01*
X633404Y886257D01*
X633972Y885752D01*
X634635Y885500D01*
X635298Y885626D01*
X635866Y886005D01*
X636245Y886510D01*
G01X642115Y893075D02*
Y885500D01*
G01X640790Y890550D02*
X643441D01*
G01X649690D02*
Y885500D01*
G01Y892570D02*
X649501Y892696D01*
Y892949D01*
X649690Y893075D01*
X649880Y892949D01*
Y892696D01*
X649690Y892570D01*
G01X657265Y885500D02*
X656697Y885626D01*
X656129Y886131D01*
X655750Y887015D01*
X655561Y888025D01*
X655750Y889035D01*
X656129Y889919D01*
X656697Y890424D01*
X657265Y890550D01*
X657834Y890424D01*
X658402Y889919D01*
X658780Y889035D01*
X658875Y888025D01*
X658780Y887015D01*
X658402Y886131D01*
X657834Y885626D01*
X657265Y885500D01*
G01X663231D02*
Y890550D01*
G01Y889287D02*
X663610Y889919D01*
X664178Y890424D01*
X664935Y890550D01*
X665598Y890424D01*
X666166Y889919D01*
X666450Y889035D01*
Y885500D01*
G01X679990D02*
X679422Y885626D01*
X678854Y886131D01*
X678475Y887015D01*
X678286Y888025D01*
X678475Y889035D01*
X678854Y889919D01*
X679422Y890424D01*
X679990Y890550D01*
X680559Y890424D01*
X681127Y889919D01*
X681505Y889035D01*
X681600Y888025D01*
X681505Y887015D01*
X681127Y886131D01*
X680559Y885626D01*
X679990Y885500D01*
G01X686997D02*
Y891939D01*
X687187Y892570D01*
X687565Y892949D01*
X688134Y893075D01*
X688702Y892823D01*
X688986Y892191D01*
G01X687850Y890045D02*
X685956D01*
G01X701106Y885500D02*
Y893075D01*
G01Y889414D02*
X701579Y890045D01*
X702053Y890424D01*
X702810Y890550D01*
X703378Y890424D01*
X704041Y889919D01*
X704325Y889161D01*
Y885500D01*
G01X710290D02*
X709722Y885626D01*
X709154Y886131D01*
X708775Y887015D01*
X708586Y888025D01*
X708775Y889035D01*
X709154Y889919D01*
X709722Y890424D01*
X710290Y890550D01*
X710859Y890424D01*
X711427Y889919D01*
X711805Y889035D01*
X711900Y888025D01*
X711805Y887015D01*
X711427Y886131D01*
X710859Y885626D01*
X710290Y885500D01*
G01X717865D02*
Y893075D01*
G01X724020Y888909D02*
X727050D01*
X726766Y889793D01*
X726293Y890297D01*
X725630Y890550D01*
X724967Y890424D01*
X724399Y890045D01*
X724020Y889161D01*
X723831Y888404D01*
Y887646D01*
X724020Y886889D01*
X724494Y886131D01*
X725062Y885626D01*
X725725Y885500D01*
X726387Y885752D01*
X727050Y886510D01*
G01X740590Y893075D02*
Y885500D01*
G01X739265Y890550D02*
X741916D01*
G01X748165Y885500D02*
X747597Y885626D01*
X747029Y886131D01*
X746650Y887015D01*
X746461Y888025D01*
X746650Y889035D01*
X747029Y889919D01*
X747597Y890424D01*
X748165Y890550D01*
X748734Y890424D01*
X749302Y889919D01*
X749680Y889035D01*
X749775Y888025D01*
X749680Y887015D01*
X749302Y886131D01*
X748734Y885626D01*
X748165Y885500D01*
G01X761706D02*
Y893075D01*
G01Y889414D02*
X762179Y890045D01*
X762653Y890424D01*
X763410Y890550D01*
X763978Y890424D01*
X764641Y889919D01*
X764925Y889161D01*
Y885500D01*
G01X770890D02*
X770322Y885626D01*
X769754Y886131D01*
X769375Y887015D01*
X769186Y888025D01*
X769375Y889035D01*
X769754Y889919D01*
X770322Y890424D01*
X770890Y890550D01*
X771459Y890424D01*
X772027Y889919D01*
X772405Y889035D01*
X772500Y888025D01*
X772405Y887015D01*
X772027Y886131D01*
X771459Y885626D01*
X770890Y885500D01*
G01X778465D02*
Y893075D01*
G01X784620Y888909D02*
X787650D01*
X787366Y889793D01*
X786893Y890297D01*
X786230Y890550D01*
X785567Y890424D01*
X784999Y890045D01*
X784620Y889161D01*
X784431Y888404D01*
Y887646D01*
X784620Y886889D01*
X785094Y886131D01*
X785662Y885626D01*
X786325Y885500D01*
X786987Y885752D01*
X787650Y886510D01*
G01X659704Y907575D02*
X661977D01*
G01X660840D02*
Y900000D01*
G01X659704D02*
X661977D01*
G01X668415Y907575D02*
Y900000D01*
G01X667090Y905050D02*
X669741D01*
G01X674570Y903409D02*
X677600D01*
X677316Y904293D01*
X676843Y904797D01*
X676180Y905050D01*
X675517Y904924D01*
X674949Y904545D01*
X674570Y903661D01*
X674381Y902904D01*
Y902146D01*
X674570Y901389D01*
X675044Y900631D01*
X675612Y900126D01*
X676275Y900000D01*
X676937Y900252D01*
X677600Y901010D01*
G01X680725Y900000D02*
Y905050D01*
G01Y903661D02*
X681009Y904293D01*
X681482Y904797D01*
X682145Y905050D01*
X682808Y904797D01*
X683281Y904293D01*
X683565Y903661D01*
Y900000D01*
G01Y903661D02*
X683850Y904293D01*
X684323Y904797D01*
X684986Y905050D01*
X685649Y904797D01*
X686122Y904293D01*
X686406Y903535D01*
Y900000D01*
G01X689720Y900884D02*
X690194Y900379D01*
X690856Y900000D01*
X691425D01*
X691993Y900252D01*
X692371Y900631D01*
X692561Y901136D01*
X692466Y901894D01*
X692087Y902272D01*
X690383Y903030D01*
X690004Y903914D01*
X690194Y904545D01*
X690572Y904924D01*
X691140Y905050D01*
X691709Y904924D01*
X692277Y904545D01*
G01X913840Y735600D02*
Y743175D01*
X912704Y741660D01*
G01Y735600D02*
X914977D01*
G01X921415Y735348D02*
X921226Y735474D01*
Y735726D01*
X921415Y735852D01*
X921605Y735726D01*
Y735474D01*
X921415Y735348D01*
G01X928990Y743175D02*
X928233Y742923D01*
X927665Y742291D01*
X927286Y741534D01*
X927002Y740524D01*
X926907Y739387D01*
X927002Y738251D01*
X927286Y737241D01*
X927665Y736484D01*
X928233Y735852D01*
X928990Y735600D01*
X929748Y735852D01*
X930316Y736484D01*
X930695Y737241D01*
X930979Y738251D01*
X931074Y739387D01*
X930979Y740524D01*
X930695Y741534D01*
X930316Y742291D01*
X929748Y742923D01*
X928990Y743175D01*
G01X933725Y735600D02*
Y740650D01*
G01Y739261D02*
X934009Y739893D01*
X934482Y740397D01*
X935145Y740650D01*
X935808Y740397D01*
X936281Y739893D01*
X936565Y739261D01*
Y735600D01*
G01Y739261D02*
X936850Y739893D01*
X937323Y740397D01*
X937986Y740650D01*
X938649Y740397D01*
X939122Y739893D01*
X939406Y739135D01*
Y735600D01*
G01X944140Y740650D02*
Y735600D01*
G01Y742670D02*
X943951Y742796D01*
Y743049D01*
X944140Y743175D01*
X944330Y743049D01*
Y742796D01*
X944140Y742670D01*
G01X951715Y735600D02*
Y743175D01*
G01X964025Y735600D02*
Y740650D01*
G01Y739261D02*
X964309Y739893D01*
X964782Y740397D01*
X965445Y740650D01*
X966108Y740397D01*
X966581Y739893D01*
X966865Y739261D01*
Y735600D01*
G01Y739261D02*
X967150Y739893D01*
X967623Y740397D01*
X968286Y740650D01*
X968949Y740397D01*
X969422Y739893D01*
X969706Y739135D01*
Y735600D01*
G01X976145D02*
Y740650D01*
G01Y739766D02*
X975766Y740271D01*
X975198Y740524D01*
X974535Y740650D01*
X973872Y740397D01*
X973304Y739893D01*
X972925Y739135D01*
X972736Y738125D01*
X972925Y737115D01*
X973304Y736357D01*
X973872Y735852D01*
X974535Y735600D01*
X975198Y735726D01*
X975766Y736105D01*
X976145Y736610D01*
G01X980595Y740650D02*
X983436Y735600D01*
G01Y740650D02*
X980595Y735600D01*
G01X924799Y750025D02*
X927071D01*
G01X925840Y751666D02*
Y748384D01*
G01X931711Y747248D02*
X935120Y755075D01*
G01X939760Y750025D02*
X942221D01*
G01X946482Y748636D02*
X947050Y748005D01*
X947713Y747626D01*
X948565Y747500D01*
X949418Y747752D01*
X950080Y748257D01*
X950554Y749141D01*
X950649Y750151D01*
X950459Y751161D01*
X949986Y751793D01*
X949323Y752297D01*
X948660Y752424D01*
X947997Y752297D01*
X947145Y751793D01*
X947429Y755075D01*
X949986D01*
G01X953300Y747500D02*
Y752550D01*
G01Y751161D02*
X953584Y751793D01*
X954057Y752297D01*
X954720Y752550D01*
X955383Y752297D01*
X955856Y751793D01*
X956140Y751161D01*
Y747500D01*
G01Y751161D02*
X956425Y751793D01*
X956898Y752297D01*
X957561Y752550D01*
X958224Y752297D01*
X958697Y751793D01*
X958981Y751035D01*
Y747500D01*
G01X963715Y752550D02*
Y747500D01*
G01Y754570D02*
X963526Y754696D01*
Y754949D01*
X963715Y755075D01*
X963905Y754949D01*
Y754696D01*
X963715Y754570D01*
G01X971290Y747500D02*
Y755075D01*
G01X908299Y787725D02*
X910571D01*
G01X909340Y789366D02*
Y786084D01*
G01X916915Y792775D02*
X916158Y792523D01*
X915590Y791891D01*
X915211Y791134D01*
X914927Y790124D01*
X914832Y788987D01*
X914927Y787851D01*
X915211Y786841D01*
X915590Y786084D01*
X916158Y785452D01*
X916915Y785200D01*
X917673Y785452D01*
X918241Y786084D01*
X918620Y786841D01*
X918904Y787851D01*
X918999Y788987D01*
X918904Y790124D01*
X918620Y791134D01*
X918241Y791891D01*
X917673Y792523D01*
X916915Y792775D01*
G01X924490Y784948D02*
X924301Y785074D01*
Y785326D01*
X924490Y785452D01*
X924680Y785326D01*
Y785074D01*
X924490Y784948D01*
G01X932065Y792775D02*
X931308Y792523D01*
X930740Y791891D01*
X930361Y791134D01*
X930077Y790124D01*
X929982Y788987D01*
X930077Y787851D01*
X930361Y786841D01*
X930740Y786084D01*
X931308Y785452D01*
X932065Y785200D01*
X932823Y785452D01*
X933391Y786084D01*
X933770Y786841D01*
X934054Y787851D01*
X934149Y788987D01*
X934054Y790124D01*
X933770Y791134D01*
X933391Y791891D01*
X932823Y792523D01*
X932065Y792775D01*
G01X939451Y785200D02*
X939640Y786841D01*
X939925Y788230D01*
X940303Y789493D01*
X940777Y790881D01*
X941534Y792775D01*
X937747D01*
G01X945132Y786336D02*
X945700Y785705D01*
X946363Y785326D01*
X947215Y785200D01*
X948068Y785452D01*
X948730Y785957D01*
X949204Y786841D01*
X949299Y787851D01*
X949109Y788861D01*
X948636Y789493D01*
X947973Y789997D01*
X947310Y790124D01*
X946647Y789997D01*
X945795Y789493D01*
X946079Y792775D01*
X948636D01*
G01X953086Y784948D02*
X956495Y792775D01*
G01X961135Y787725D02*
X963596D01*
G01X969940Y792775D02*
X969183Y792523D01*
X968615Y791891D01*
X968236Y791134D01*
X967952Y790124D01*
X967857Y788987D01*
X967952Y787851D01*
X968236Y786841D01*
X968615Y786084D01*
X969183Y785452D01*
X969940Y785200D01*
X970698Y785452D01*
X971266Y786084D01*
X971645Y786841D01*
X971929Y787851D01*
X972024Y788987D01*
X971929Y790124D01*
X971645Y791134D01*
X971266Y791891D01*
X970698Y792523D01*
X969940Y792775D01*
G01X974675Y785200D02*
Y790250D01*
G01Y788861D02*
X974959Y789493D01*
X975432Y789997D01*
X976095Y790250D01*
X976758Y789997D01*
X977231Y789493D01*
X977515Y788861D01*
Y785200D01*
G01Y788861D02*
X977800Y789493D01*
X978273Y789997D01*
X978936Y790250D01*
X979599Y789997D01*
X980072Y789493D01*
X980356Y788735D01*
Y785200D01*
G01X982250D02*
Y790250D01*
G01Y788861D02*
X982534Y789493D01*
X983007Y789997D01*
X983670Y790250D01*
X984333Y789997D01*
X984806Y789493D01*
X985090Y788861D01*
Y785200D01*
G01Y788861D02*
X985375Y789493D01*
X985848Y789997D01*
X986511Y790250D01*
X987174Y789997D01*
X987647Y789493D01*
X987931Y788735D01*
Y785200D01*
G01X924799Y763025D02*
X927071D01*
G01X925840Y764666D02*
Y761384D01*
G01X931711Y760248D02*
X935120Y768075D01*
G01X939760Y763025D02*
X942221D01*
G01X946482Y761636D02*
X947050Y761005D01*
X947713Y760626D01*
X948565Y760500D01*
X949418Y760752D01*
X950080Y761257D01*
X950554Y762141D01*
X950649Y763151D01*
X950459Y764161D01*
X949986Y764793D01*
X949323Y765297D01*
X948660Y765424D01*
X947997Y765297D01*
X947145Y764793D01*
X947429Y768075D01*
X949986D01*
G01X953300Y760500D02*
Y765550D01*
G01Y764161D02*
X953584Y764793D01*
X954057Y765297D01*
X954720Y765550D01*
X955383Y765297D01*
X955856Y764793D01*
X956140Y764161D01*
Y760500D01*
G01Y764161D02*
X956425Y764793D01*
X956898Y765297D01*
X957561Y765550D01*
X958224Y765297D01*
X958697Y764793D01*
X958981Y764035D01*
Y760500D01*
G01X963715Y765550D02*
Y760500D01*
G01Y767570D02*
X963526Y767696D01*
Y767949D01*
X963715Y768075D01*
X963905Y767949D01*
Y767696D01*
X963715Y767570D01*
G01X971290Y760500D02*
Y768075D01*
G01X924799Y775525D02*
X927071D01*
G01X925840Y777166D02*
Y773884D01*
G01X931711Y772748D02*
X935120Y780575D01*
G01X939760Y775525D02*
X942221D01*
G01X948565Y780575D02*
X947808Y780323D01*
X947240Y779691D01*
X946861Y778934D01*
X946577Y777924D01*
X946482Y776787D01*
X946577Y775651D01*
X946861Y774641D01*
X947240Y773884D01*
X947808Y773252D01*
X948565Y773000D01*
X949323Y773252D01*
X949891Y773884D01*
X950270Y774641D01*
X950554Y775651D01*
X950649Y776787D01*
X950554Y777924D01*
X950270Y778934D01*
X949891Y779691D01*
X949323Y780323D01*
X948565Y780575D01*
G01X956140Y772748D02*
X955951Y772874D01*
Y773126D01*
X956140Y773252D01*
X956330Y773126D01*
Y772874D01*
X956140Y772748D01*
G01X963715Y780575D02*
X962958Y780323D01*
X962390Y779691D01*
X962011Y778934D01*
X961727Y777924D01*
X961632Y776787D01*
X961727Y775651D01*
X962011Y774641D01*
X962390Y773884D01*
X962958Y773252D01*
X963715Y773000D01*
X964473Y773252D01*
X965041Y773884D01*
X965420Y774641D01*
X965704Y775651D01*
X965799Y776787D01*
X965704Y777924D01*
X965420Y778934D01*
X965041Y779691D01*
X964473Y780323D01*
X963715Y780575D01*
G01X969207Y774136D02*
X969775Y773505D01*
X970438Y773126D01*
X971290Y773000D01*
X972143Y773252D01*
X972805Y773757D01*
X973279Y774641D01*
X973374Y775651D01*
X973184Y776661D01*
X972711Y777293D01*
X972048Y777797D01*
X971385Y777924D01*
X970722Y777797D01*
X969870Y777293D01*
X970154Y780575D01*
X972711D01*
G01X976025Y773000D02*
Y778050D01*
G01Y776661D02*
X976309Y777293D01*
X976782Y777797D01*
X977445Y778050D01*
X978108Y777797D01*
X978581Y777293D01*
X978865Y776661D01*
Y773000D01*
G01Y776661D02*
X979150Y777293D01*
X979623Y777797D01*
X980286Y778050D01*
X980949Y777797D01*
X981422Y777293D01*
X981706Y776535D01*
Y773000D01*
G01X983600D02*
Y778050D01*
G01Y776661D02*
X983884Y777293D01*
X984357Y777797D01*
X985020Y778050D01*
X985683Y777797D01*
X986156Y777293D01*
X986440Y776661D01*
Y773000D01*
G01Y776661D02*
X986725Y777293D01*
X987198Y777797D01*
X987861Y778050D01*
X988524Y777797D01*
X988997Y777293D01*
X989281Y776535D01*
Y773000D01*
G01X924799Y800025D02*
X927071D01*
G01X925840Y801666D02*
Y798384D01*
G01X931711Y797248D02*
X935120Y805075D01*
G01X939760Y800025D02*
X942221D01*
G01X946766Y803813D02*
X947335Y804570D01*
X947997Y804949D01*
X948755Y805075D01*
X949702Y804823D01*
X950365Y804191D01*
X950554Y803434D01*
X950459Y802676D01*
X950080Y802045D01*
X948187Y800782D01*
X947335Y799899D01*
X946766Y798636D01*
X946577Y797500D01*
X950554D01*
G01X953300D02*
Y802550D01*
G01Y801161D02*
X953584Y801793D01*
X954057Y802297D01*
X954720Y802550D01*
X955383Y802297D01*
X955856Y801793D01*
X956140Y801161D01*
Y797500D01*
G01Y801161D02*
X956425Y801793D01*
X956898Y802297D01*
X957561Y802550D01*
X958224Y802297D01*
X958697Y801793D01*
X958981Y801035D01*
Y797500D01*
G01X963715Y802550D02*
Y797500D01*
G01Y804570D02*
X963526Y804696D01*
Y804949D01*
X963715Y805075D01*
X963905Y804949D01*
Y804696D01*
X963715Y804570D01*
G01X971290Y797500D02*
Y805075D01*
G01X924799Y838025D02*
X927071D01*
G01X925840Y839666D02*
Y836384D01*
G01X931711Y835248D02*
X935120Y843075D01*
G01X939760Y838025D02*
X942221D01*
G01X946766Y841813D02*
X947335Y842570D01*
X947997Y842949D01*
X948755Y843075D01*
X949702Y842823D01*
X950365Y842191D01*
X950554Y841434D01*
X950459Y840676D01*
X950080Y840045D01*
X948187Y838782D01*
X947335Y837899D01*
X946766Y836636D01*
X946577Y835500D01*
X950554D01*
G01X953300D02*
Y840550D01*
G01Y839161D02*
X953584Y839793D01*
X954057Y840297D01*
X954720Y840550D01*
X955383Y840297D01*
X955856Y839793D01*
X956140Y839161D01*
Y835500D01*
G01Y839161D02*
X956425Y839793D01*
X956898Y840297D01*
X957561Y840550D01*
X958224Y840297D01*
X958697Y839793D01*
X958981Y839035D01*
Y835500D01*
G01X963715Y840550D02*
Y835500D01*
G01Y842570D02*
X963526Y842696D01*
Y842949D01*
X963715Y843075D01*
X963905Y842949D01*
Y842696D01*
X963715Y842570D01*
G01X971290Y835500D02*
Y843075D01*
G01X924799Y820525D02*
X927071D01*
G01X925840Y822166D02*
Y818884D01*
G01X931711Y817748D02*
X935120Y825575D01*
G01X939760Y820525D02*
X942221D01*
G01X946482Y819515D02*
X947050Y818631D01*
X947808Y818126D01*
X948660Y818000D01*
X949418Y818126D01*
X950175Y818757D01*
X950649Y819515D01*
X950743Y820272D01*
X950554Y821156D01*
X949891Y821787D01*
X949228Y822040D01*
X948376D01*
G01X949228D02*
X949796Y822419D01*
X950270Y823050D01*
X950459Y823807D01*
X950270Y824565D01*
X949796Y825196D01*
X948944Y825575D01*
X948092Y825449D01*
X947240Y824944D01*
G01X953300Y818000D02*
Y823050D01*
G01Y821661D02*
X953584Y822293D01*
X954057Y822797D01*
X954720Y823050D01*
X955383Y822797D01*
X955856Y822293D01*
X956140Y821661D01*
Y818000D01*
G01Y821661D02*
X956425Y822293D01*
X956898Y822797D01*
X957561Y823050D01*
X958224Y822797D01*
X958697Y822293D01*
X958981Y821535D01*
Y818000D01*
G01X963715Y823050D02*
Y818000D01*
G01Y825070D02*
X963526Y825196D01*
Y825449D01*
X963715Y825575D01*
X963905Y825449D01*
Y825196D01*
X963715Y825070D01*
G01X971290Y818000D02*
Y825575D01*
G01X924799Y863525D02*
X927071D01*
G01X925840Y865166D02*
Y861884D01*
G01X933415Y861000D02*
Y868575D01*
X932279Y867060D01*
G01Y861000D02*
X934552D01*
G01X939286Y860748D02*
X942695Y868575D01*
G01X947335Y863525D02*
X949796D01*
G01X954057Y862515D02*
X954625Y861631D01*
X955383Y861126D01*
X956235Y861000D01*
X956993Y861126D01*
X957750Y861757D01*
X958224Y862515D01*
X958318Y863272D01*
X958129Y864156D01*
X957466Y864787D01*
X956803Y865040D01*
X955951D01*
G01X956803D02*
X957371Y865419D01*
X957845Y866050D01*
X958034Y866807D01*
X957845Y867565D01*
X957371Y868196D01*
X956519Y868575D01*
X955667Y868449D01*
X954815Y867944D01*
G01X960875Y861000D02*
Y866050D01*
G01Y864661D02*
X961159Y865293D01*
X961632Y865797D01*
X962295Y866050D01*
X962958Y865797D01*
X963431Y865293D01*
X963715Y864661D01*
Y861000D01*
G01Y864661D02*
X964000Y865293D01*
X964473Y865797D01*
X965136Y866050D01*
X965799Y865797D01*
X966272Y865293D01*
X966556Y864535D01*
Y861000D01*
G01X971290Y866050D02*
Y861000D01*
G01Y868070D02*
X971101Y868196D01*
Y868449D01*
X971290Y868575D01*
X971480Y868449D01*
Y868196D01*
X971290Y868070D01*
G01X978865Y861000D02*
Y868575D01*
G01X924799Y875525D02*
X927071D01*
G01X925840Y877166D02*
Y873884D01*
G01X931616Y879313D02*
X932185Y880070D01*
X932847Y880449D01*
X933605Y880575D01*
X934552Y880323D01*
X935215Y879691D01*
X935404Y878934D01*
X935309Y878176D01*
X934930Y877545D01*
X933037Y876282D01*
X932185Y875399D01*
X931616Y874136D01*
X931427Y873000D01*
X935404D01*
G01X939286Y872748D02*
X942695Y880575D01*
G01X947335Y875525D02*
X949796D01*
G01X957277Y873000D02*
Y880575D01*
X953773Y875146D01*
X958508D01*
G01X960875Y873000D02*
Y878050D01*
G01Y876661D02*
X961159Y877293D01*
X961632Y877797D01*
X962295Y878050D01*
X962958Y877797D01*
X963431Y877293D01*
X963715Y876661D01*
Y873000D01*
G01Y876661D02*
X964000Y877293D01*
X964473Y877797D01*
X965136Y878050D01*
X965799Y877797D01*
X966272Y877293D01*
X966556Y876535D01*
Y873000D01*
G01X971290Y878050D02*
Y873000D01*
G01Y880070D02*
X971101Y880196D01*
Y880449D01*
X971290Y880575D01*
X971480Y880449D01*
Y880196D01*
X971290Y880070D01*
G01X978865Y873000D02*
Y880575D01*
G01X919840Y908575D02*
Y901000D01*
G01X917663Y908575D02*
X922018D01*
G01X927415Y901000D02*
X926847Y901126D01*
X926279Y901631D01*
X925900Y902515D01*
X925711Y903525D01*
X925900Y904535D01*
X926279Y905419D01*
X926847Y905924D01*
X927415Y906050D01*
X927984Y905924D01*
X928552Y905419D01*
X928930Y904535D01*
X929025Y903525D01*
X928930Y902515D01*
X928552Y901631D01*
X927984Y901126D01*
X927415Y901000D01*
G01X934990D02*
Y908575D01*
G01X941145Y904409D02*
X944175D01*
X943891Y905293D01*
X943418Y905797D01*
X942755Y906050D01*
X942092Y905924D01*
X941524Y905545D01*
X941145Y904661D01*
X940956Y903904D01*
Y903146D01*
X941145Y902389D01*
X941619Y901631D01*
X942187Y901126D01*
X942850Y901000D01*
X943512Y901252D01*
X944175Y902010D01*
G01X948815Y901000D02*
Y906050D01*
G01Y905040D02*
X949288Y905545D01*
X949762Y905924D01*
X950425Y906050D01*
X950898Y905924D01*
X951466Y905545D01*
G01X959420Y901000D02*
Y906050D01*
G01Y905166D02*
X959041Y905671D01*
X958473Y905924D01*
X957810Y906050D01*
X957147Y905797D01*
X956579Y905293D01*
X956200Y904535D01*
X956011Y903525D01*
X956200Y902515D01*
X956579Y901757D01*
X957147Y901252D01*
X957810Y901000D01*
X958473Y901126D01*
X959041Y901505D01*
X959420Y902010D01*
G01X963681Y901000D02*
Y906050D01*
G01Y904787D02*
X964060Y905419D01*
X964628Y905924D01*
X965385Y906050D01*
X966048Y905924D01*
X966616Y905419D01*
X966900Y904535D01*
Y901000D01*
G01X974380Y905419D02*
X973718Y905924D01*
X973150Y906050D01*
X972392Y905797D01*
X971824Y905293D01*
X971445Y904409D01*
X971350Y903525D01*
X971445Y902641D01*
X971824Y901884D01*
X972392Y901252D01*
X973150Y901000D01*
X973812Y901252D01*
X974380Y901757D01*
G01X979020Y904409D02*
X982050D01*
X981766Y905293D01*
X981293Y905797D01*
X980630Y906050D01*
X979967Y905924D01*
X979399Y905545D01*
X979020Y904661D01*
X978831Y903904D01*
Y903146D01*
X979020Y902389D01*
X979494Y901631D01*
X980062Y901126D01*
X980725Y901000D01*
X981387Y901252D01*
X982050Y902010D01*
G01X924799Y888025D02*
X927071D01*
G01X925840Y889666D02*
Y886384D01*
G01X931711Y885248D02*
X935120Y893075D01*
G01X939760Y888025D02*
X942221D01*
G01X946482Y887015D02*
X947050Y886131D01*
X947808Y885626D01*
X948660Y885500D01*
X949418Y885626D01*
X950175Y886257D01*
X950649Y887015D01*
X950743Y887772D01*
X950554Y888656D01*
X949891Y889287D01*
X949228Y889540D01*
X948376D01*
G01X949228D02*
X949796Y889919D01*
X950270Y890550D01*
X950459Y891307D01*
X950270Y892065D01*
X949796Y892696D01*
X948944Y893075D01*
X948092Y892949D01*
X947240Y892444D01*
G01X953300Y885500D02*
Y890550D01*
G01Y889161D02*
X953584Y889793D01*
X954057Y890297D01*
X954720Y890550D01*
X955383Y890297D01*
X955856Y889793D01*
X956140Y889161D01*
Y885500D01*
G01Y889161D02*
X956425Y889793D01*
X956898Y890297D01*
X957561Y890550D01*
X958224Y890297D01*
X958697Y889793D01*
X958981Y889035D01*
Y885500D01*
G01X963715Y890550D02*
Y885500D01*
G01Y892570D02*
X963526Y892696D01*
Y892949D01*
X963715Y893075D01*
X963905Y892949D01*
Y892696D01*
X963715Y892570D01*
G01X971290Y885500D02*
Y893075D01*
G01X-312900Y1474400D02*
Y605600D01*
X1228000D01*
Y1474400D01*
X-312900D01*
G01Y1056000D02*
X1228000D01*
G01X-127400Y842800D02*
Y864000D01*
X-127500Y864100D01*
X-131900Y859700D01*
G01X-127200Y863900D02*
Y863800D01*
X-123100Y859700D01*
G01X-126400Y903500D02*
X-126300D01*
X-123200Y906600D01*
G01X-126400Y903900D02*
X-126000D01*
G01X-126300Y923800D02*
Y904000D01*
X-126600Y903700D01*
X-129600Y906700D01*
G01X-89400Y864000D02*
X-149200D01*
X-149300Y864100D01*
G01X-89500Y903500D02*
X-149400D01*
G01X-130827Y1308797D02*
X-130817Y1296797D01*
G01X-130827Y1308797D02*
X-106806Y1284817D01*
X-106800Y1245500D01*
G01X-130827Y1308797D02*
X-118827Y1308807D01*
G01X-83000Y805400D02*
Y805200D01*
X-80500Y802700D01*
G01X-89300Y805500D02*
Y805200D01*
X-91200Y803300D01*
G01X-83100Y848100D02*
Y799100D01*
X-83200Y799000D01*
G01X-89100Y847900D02*
Y798700D01*
X-89200Y798600D01*
G01X-101400Y778500D02*
X-62500D01*
X-62200Y778800D01*
X-64800Y781400D01*
G01X-67700Y805300D02*
X-82900D01*
X-83000Y805400D01*
X-80400Y808000D01*
G01X-113900Y805300D02*
X-89300D01*
X-89100Y805500D01*
X-91500Y807900D01*
G01X-89100Y922600D02*
Y994600D01*
G01X-88800Y977400D02*
Y977300D01*
X-87000Y975500D01*
G01X-75300Y977400D02*
X-88700D01*
X-88900Y977600D01*
X-86800Y979700D01*
G01X-73380Y1289970D02*
X-31380D01*
G01X-73380D02*
X-65380Y1281970D01*
G01X-73380Y1289970D02*
X-65380Y1297970D01*
G01X-84920Y1316540D02*
X-60920Y1340540D01*
X-28920D01*
G01X-84920Y1316540D02*
Y1328540D01*
G01Y1316540D02*
X-72920D01*
G01X-37100Y778900D02*
Y778800D01*
X-33900Y775600D01*
G01X-5900Y778800D02*
X-37000D01*
X-37200Y779000D01*
X-34200Y782000D01*
G01X-62300Y778500D02*
X-62500D01*
X-65100Y775900D01*
G01X-37200Y811400D02*
Y763400D01*
G01X-62200Y810900D02*
Y763300D01*
G01X-37200Y810900D02*
X57200D01*
X57800Y810300D01*
G01X-38200Y957100D02*
X51100D01*
X51600Y957600D01*
G01X-31000Y977600D02*
X-10100D01*
X-9900Y977800D01*
X-12700Y980600D01*
X-12800D01*
G01X15800Y811400D02*
X16000D01*
X19600Y815000D01*
G01X15700Y811300D02*
X15200D01*
X11300Y815200D01*
G01X15600Y865200D02*
Y811500D01*
X15000Y810900D01*
G01X14500Y956500D02*
Y905300D01*
X15000Y904800D01*
G01X14500Y956900D02*
X17700Y953700D01*
G01X14400Y957000D02*
X11000Y953600D01*
G01X-10000Y919500D02*
Y992000D01*
X-9900Y992100D01*
G01X-10000Y977700D02*
Y977600D01*
X-12600Y975000D01*
G01X330300Y1474500D02*
Y605600D01*
G01X354000Y733000D02*
X1007000D01*
Y913000D01*
X354000D01*
Y733000D01*
G01X1007000Y745500D02*
X354000D01*
G01X382000Y733000D02*
Y758000D01*
G01Y733000D02*
X496000D01*
Y896000D01*
G01X354000Y770500D02*
Y758000D01*
X382000D01*
Y770500D01*
G01X354000Y795500D02*
Y783000D01*
X382000D01*
Y795500D01*
G01X354000Y783000D02*
Y770500D01*
X382000D01*
Y783000D01*
G01X354000Y808000D02*
Y795500D01*
X382000D01*
Y808000D01*
G01X354000Y820500D02*
Y808000D01*
X382000D01*
Y820500D01*
G01X354000Y845500D02*
Y833000D01*
X382000D01*
Y845500D01*
G01X381500Y873500D02*
X382000D01*
Y817000D01*
G01X354000Y870500D02*
Y858000D01*
X382000D01*
Y870500D01*
G01X354000Y883000D02*
Y870500D01*
X382000D01*
Y883000D01*
G01X354000Y895500D02*
Y883000D01*
X382000D01*
Y895500D01*
G01X1007000D02*
X354000D01*
G01X363000Y913000D02*
X1007000D01*
Y895500D01*
X354000D01*
Y913000D01*
X363000D01*
G01X382000Y895500D02*
Y913000D01*
G01Y883000D02*
X496000D01*
Y895500D01*
G01X1007000Y758000D02*
X496000D01*
G01X1007000Y770500D02*
X496000D01*
G01Y783000D02*
X1007000D01*
Y795500D01*
G01D02*
X496000D01*
G01X1007000Y808000D02*
X496000D01*
G01X1007000Y833000D02*
X496000D01*
G01X1007000Y870500D02*
X496000D01*
G01X1007000Y858000D02*
X496000D01*
G01Y895500D02*
Y913000D01*
G01X1007000Y883000D02*
X496000D01*
G01X905500Y733000D02*
Y913000D01*
G01X915500Y758000D02*
X1007000D01*
Y770500D01*
G01X915500D02*
X1007000D01*
Y783000D01*
G01X915500Y795500D02*
X1007000D01*
Y808000D01*
G01X915500D02*
X1007000D01*
Y833000D01*
G01X915500D02*
X1007000D01*
Y870500D01*
G01X915500Y858000D02*
X1007000D01*
Y870500D01*
G01X915500D02*
X1007000D01*
Y883000D01*
G01X915500D02*
X1007000D01*
Y895500D01*
G01X988200Y1056000D02*
Y1056100D01*
M02*
